G04 ================== begin FILE IDENTIFICATION RECORD ==================*
G04 Layout Name:  15105-sa.brd*
G04 Film Name:    TSMD*
G04 File Format:  Gerber RS274X*
G04 File Origin:  Cadence Allegro 16.5-S056*
G04 Origin Date:  Wed Nov 16 02:01:58 2016*
G04 *
G04 Layer:  VIA CLASS/PASTEMASK_TOP*
G04 Layer:  PIN/PASTEMASK_TOP*
G04 Layer:  PACKAGE GEOMETRY/PASTEMASK_TOP*
G04 Layer:  DRAWING FORMAT/LAYER_PCB_STORY*
G04 Layer:  DRAWING FORMAT/LAYER_PAST_T*
G04 Layer:  BOARD GEOMETRY/PANEL_OUTLINE*
G04 *
G04 Offset:    (0.00 0.00)*
G04 Mirror:    No*
G04 Mode:      Positive*
G04 Rotation:  0*
G04 FullContactRelief:  No*
G04 UndefLineWidth:     6.00*
G04 ================== end FILE IDENTIFICATION RECORD ====================*
%FSLAX35Y35*MOIN*%
%IR0*IPPOS*OFA0.00000B0.00000*MIA0B0*SFA1.00000B1.00000*%
%AMMACRO35*
4,1,40,.013,.017,
-.013,.017,
-.013695,.016939,
-.014368,.016759,
-.015,.016464,
-.015571,.016064,
-.016064,.015571,
-.016464,.015,
-.016759,.014368,
-.016939,.013695,
-.017,.013,
-.017,-.013,
-.016939,-.013695,
-.016759,-.014368,
-.016464,-.015,
-.016064,-.015571,
-.015571,-.016064,
-.015,-.016464,
-.014368,-.016759,
-.013695,-.016939,
-.013,-.017,
.013,-.017,
.013695,-.016939,
.014368,-.016759,
.015,-.016464,
.015571,-.016064,
.016064,-.015571,
.016464,-.015,
.016759,-.014368,
.016939,-.013695,
.017,-.013,
.017,.013,
.016939,.013695,
.016759,.014368,
.016464,.015,
.016064,.015571,
.015571,.016064,
.015,.016464,
.014368,.016759,
.013695,.016939,
.013,.017,
0.0*
%
%ADD35MACRO35*%
%AMMACRO23*
4,1,40,.017,-.013,
.017,.013,
.016939,.013695,
.016759,.014368,
.016464,.015,
.016064,.015571,
.015571,.016064,
.015,.016464,
.014368,.016759,
.013695,.016939,
.013,.017,
-.013,.017,
-.013695,.016939,
-.014368,.016759,
-.015,.016464,
-.015571,.016064,
-.016064,.015571,
-.016464,.015,
-.016759,.014368,
-.016939,.013695,
-.017,.013,
-.017,-.013,
-.016939,-.013695,
-.016759,-.014368,
-.016464,-.015,
-.016064,-.015571,
-.015571,-.016064,
-.015,-.016464,
-.014368,-.016759,
-.013695,-.016939,
-.013,-.017,
.013,-.017,
.013695,-.016939,
.014368,-.016759,
.015,-.016464,
.015571,-.016064,
.016064,-.015571,
.016464,-.015,
.016759,-.014368,
.016939,-.013695,
.017,-.013,
0.0*
%
%ADD23MACRO23*%
%AMMACRO94*
4,1,3,.025,.0125,
0.0,-.0125,
-.025,.0125,
.025,.0125,
0.0*
%
%ADD94MACRO94*%
%AMMACRO69*
4,1,15,-.0275,-.115,
-.0275,.02323,
-.02431,.026923,
-.021809,.031114,
-.020074,.035675,
-.019157,.040469,
-.019087,.045348,
-.019865,.050166,
-.021468,.054776,
-.023847,.059037,
-.02693,.06282,
-.0275,.06339,
-.0275,.115,
.0275,.115,
.0275,-.115,
-.0275,-.115,
0.0*
%
%ADD69MACRO69*%
%ADD82R,.081X.1*%
%ADD101R,.045X.11*%
%ADD121R,.055X.11*%
%ADD88R,.111X.028*%
%AMMACRO112*
4,1,3,0.0,-.0125,
-.025,.0125,
.025,.0125,
0.0,-.0125,
0.0*
%
%ADD112MACRO112*%
%ADD127C,.02*%
%ADD66R,.012X.008*%
%ADD33C,.04*%
%ADD92C,.032*%
%ADD71C,.014*%
%ADD123R,.008X.06*%
%AMMACRO60*
4,1,40,.004,.007,
-.004,.007,
-.004347,.00697,
-.004684,.006879,
-.005,.006732,
-.005286,.006532,
-.005532,.006286,
-.005732,.006,
-.005879,.005684,
-.00597,.005347,
-.006,.005,
-.006,-.005,
-.00597,-.005347,
-.005879,-.005684,
-.005732,-.006,
-.005532,-.006286,
-.005286,-.006532,
-.005,-.006732,
-.004684,-.006879,
-.004347,-.00697,
-.004,-.007,
.004,-.007,
.004347,-.00697,
.004684,-.006879,
.005,-.006732,
.005286,-.006532,
.005532,-.006286,
.005732,-.006,
.005879,-.005684,
.00597,-.005347,
.006,-.005,
.006,.005,
.00597,.005347,
.005879,.005684,
.005732,.006,
.005532,.006286,
.005286,.006532,
.005,.006732,
.004684,.006879,
.004347,.00697,
.004,.007,
0.0*
%
%ADD60MACRO60*%
%ADD72C,.016*%
%ADD119R,.092X.128*%
%ADD106R,.039X.108*%
%ADD128C,.018*%
%ADD26C,.028*%
%ADD114R,.135X.098*%
%ADD126R,.044X.044*%
%AMMACRO28*
4,1,40,.0225,-.007,
.022378,-.008389,
.022018,-.009736,
.021428,-.011,
.020628,-.012142,
.019642,-.013128,
.0185,-.013928,
.017236,-.014518,
.015889,-.014878,
.0145,-.015,
-.0145,-.015,
-.015889,-.014878,
-.017236,-.014518,
-.0185,-.013928,
-.019642,-.013128,
-.020628,-.012142,
-.021428,-.011,
-.022018,-.009736,
-.022378,-.008389,
-.0225,-.007,
-.0225,.007,
-.022378,.008389,
-.022018,.009736,
-.021428,.011,
-.020628,.012142,
-.019642,.013128,
-.0185,.013928,
-.017236,.014518,
-.015889,.014878,
-.0145,.015,
.0145,.015,
.015889,.014878,
.017236,.014518,
.0185,.013928,
.019642,.013128,
.020628,.012142,
.021428,.011,
.022018,.009736,
.022378,.008389,
.0225,.007,
.0225,-.007,
0.0*
%
%ADD28MACRO28*%
%ADD122R,.045X.045*%
%AMMACRO58*
4,1,40,-.007,-.0225,
-.008389,-.022378,
-.009736,-.022018,
-.011,-.021428,
-.012142,-.020628,
-.013128,-.019642,
-.013928,-.0185,
-.014518,-.017236,
-.014878,-.015889,
-.015,-.0145,
-.015,.0145,
-.014878,.015889,
-.014518,.017236,
-.013928,.0185,
-.013128,.019642,
-.012142,.020628,
-.011,.021428,
-.009736,.022018,
-.008389,.022378,
-.007,.0225,
.007,.0225,
.008389,.022378,
.009736,.022018,
.011,.021428,
.012142,.020628,
.013128,.019642,
.013928,.0185,
.014518,.017236,
.014878,.015889,
.015,.0145,
.015,-.0145,
.014878,-.015889,
.014518,-.017236,
.013928,-.0185,
.013128,-.019642,
.012142,-.020628,
.011,-.021428,
.009736,-.022018,
.008389,-.022378,
.007,-.0225,
-.007,-.0225,
0.0*
%
%ADD58MACRO58*%
%AMMACRO29*
4,1,40,.007,.011,
-.007,.011,
-.007695,.010939,
-.008368,.010759,
-.009,.010464,
-.009571,.010064,
-.010064,.009571,
-.010464,.009,
-.010759,.008368,
-.010939,.007695,
-.011,.007,
-.011,-.007,
-.010939,-.007695,
-.010759,-.008368,
-.010464,-.009,
-.010064,-.009571,
-.009571,-.010064,
-.009,-.010464,
-.008368,-.010759,
-.007695,-.010939,
-.007,-.011,
.007,-.011,
.007695,-.010939,
.008368,-.010759,
.009,-.010464,
.009571,-.010064,
.010064,-.009571,
.010464,-.009,
.010759,-.008368,
.010939,-.007695,
.011,-.007,
.011,.007,
.010939,.007695,
.010759,.008368,
.010464,.009,
.010064,.009571,
.009571,.010064,
.009,.010464,
.008368,.010759,
.007695,.010939,
.007,.011,
0.0*
%
%ADD29MACRO29*%
%AMMACRO20*
4,1,40,.011,-.007,
.011,.007,
.010939,.007695,
.010759,.008368,
.010464,.009,
.010064,.009571,
.009571,.010064,
.009,.010464,
.008368,.010759,
.007695,.010939,
.007,.011,
-.007,.011,
-.007695,.010939,
-.008368,.010759,
-.009,.010464,
-.009571,.010064,
-.010064,.009571,
-.010464,.009,
-.010759,.008368,
-.010939,.007695,
-.011,.007,
-.011,-.007,
-.010939,-.007695,
-.010759,-.008368,
-.010464,-.009,
-.010064,-.009571,
-.009571,-.010064,
-.009,-.010464,
-.008368,-.010759,
-.007695,-.010939,
-.007,-.011,
.007,-.011,
.007695,-.010939,
.008368,-.010759,
.009,-.010464,
.009571,-.010064,
.010064,-.009571,
.010464,-.009,
.010759,-.008368,
.010939,-.007695,
.011,-.007,
0.0*
%
%ADD20MACRO20*%
%AMMACRO46*
4,1,20,.032,-.047,
.0155,-.047,
.0155,-.074,
.0045,-.074,
.0045,-.049,
-.0045,-.049,
-.0045,-.074,
-.0155,-.074,
-.0155,-.047,
-.032,-.047,
-.032,.047,
-.0155,.047,
-.0155,.074,
-.0045,.074,
-.0045,.049,
.0045,.049,
.0045,.074,
.0155,.074,
.0155,.047,
.032,.047,
.032,-.047,
0.0*
%
%ADD46MACRO46*%
%AMMACRO110*
4,1,40,-.012,.024,
.012,.024,
.013389,.023878,
.014736,.023518,
.016,.022928,
.017142,.022128,
.018128,.021142,
.018928,.02,
.019518,.018736,
.019878,.017389,
.02,.016,
.02,-.016,
.019878,-.017389,
.019518,-.018736,
.018928,-.02,
.018128,-.021142,
.017142,-.022128,
.016,-.022928,
.014736,-.023518,
.013389,-.023878,
.012,-.024,
-.012,-.024,
-.013389,-.023878,
-.014736,-.023518,
-.016,-.022928,
-.017142,-.022128,
-.018128,-.021142,
-.018928,-.02,
-.019518,-.018736,
-.019878,-.017389,
-.02,-.016,
-.02,.016,
-.019878,.017389,
-.019518,.018736,
-.018928,.02,
-.018128,.021142,
-.017142,.022128,
-.016,.022928,
-.014736,.023518,
-.013389,.023878,
-.012,.024,
0.0*
%
%ADD110MACRO110*%
%AMMACRO109*
4,1,20,-.047,-.032,
-.047,-.0155,
-.074,-.0155,
-.074,-.0045,
-.049,-.0045,
-.049,.0045,
-.074,.0045,
-.074,.0155,
-.047,.0155,
-.047,.032,
.047,.032,
.047,.0155,
.074,.0155,
.074,.0045,
.049,.0045,
.049,-.0045,
.074,-.0045,
.074,-.0155,
.047,-.0155,
.047,-.032,
-.047,-.032,
0.0*
%
%ADD109MACRO109*%
%AMMACRO43*
4,1,40,-.012,.008,
-.012,-.008,
-.011939,-.008695,
-.011759,-.009368,
-.011464,-.01,
-.011064,-.010571,
-.010571,-.011064,
-.01,-.011464,
-.009368,-.011759,
-.008695,-.011939,
-.008,-.012,
.008,-.012,
.008695,-.011939,
.009368,-.011759,
.01,-.011464,
.010571,-.011064,
.011064,-.010571,
.011464,-.01,
.011759,-.009368,
.011939,-.008695,
.012,-.008,
.012,.008,
.011939,.008695,
.011759,.009368,
.011464,.01,
.011064,.010571,
.010571,.011064,
.01,.011464,
.009368,.011759,
.008695,.011939,
.008,.012,
-.008,.012,
-.008695,.011939,
-.009368,.011759,
-.01,.011464,
-.010571,.011064,
-.011064,.010571,
-.011464,.01,
-.011759,.009368,
-.011939,.008695,
-.012,.008,
0.0*
%
%ADD43MACRO43*%
%AMMACRO10*
4,1,40,.008,.012,
-.008,.012,
-.008695,.011939,
-.009368,.011759,
-.01,.011464,
-.010571,.011064,
-.011064,.010571,
-.011464,.01,
-.011759,.009368,
-.011939,.008695,
-.012,.008,
-.012,-.008,
-.011939,-.008695,
-.011759,-.009368,
-.011464,-.01,
-.011064,-.010571,
-.010571,-.011064,
-.01,-.011464,
-.009368,-.011759,
-.008695,-.011939,
-.008,-.012,
.008,-.012,
.008695,-.011939,
.009368,-.011759,
.01,-.011464,
.010571,-.011064,
.011064,-.010571,
.011464,-.01,
.011759,-.009368,
.011939,-.008695,
.012,-.008,
.012,.008,
.011939,.008695,
.011759,.009368,
.011464,.01,
.011064,.010571,
.010571,.011064,
.01,.011464,
.009368,.011759,
.008695,.011939,
.008,.012,
0.0*
%
%ADD10MACRO10*%
%AMMACRO36*
4,1,40,-.013,-.017,
.013,-.017,
.013695,-.016939,
.014368,-.016759,
.015,-.016464,
.015571,-.016064,
.016064,-.015571,
.016464,-.015,
.016759,-.014368,
.016939,-.013695,
.017,-.013,
.017,.013,
.016939,.013695,
.016759,.014368,
.016464,.015,
.016064,.015571,
.015571,.016064,
.015,.016464,
.014368,.016759,
.013695,.016939,
.013,.017,
-.013,.017,
-.013695,.016939,
-.014368,.016759,
-.015,.016464,
-.015571,.016064,
-.016064,.015571,
-.016464,.015,
-.016759,.014368,
-.016939,.013695,
-.017,.013,
-.017,-.013,
-.016939,-.013695,
-.016759,-.014368,
-.016464,-.015,
-.016064,-.015571,
-.015571,-.016064,
-.015,-.016464,
-.014368,-.016759,
-.013695,-.016939,
-.013,-.017,
0.0*
%
%ADD36MACRO36*%
%AMMACRO15*
4,1,40,-.017,.013,
-.017,-.013,
-.016939,-.013695,
-.016759,-.014368,
-.016464,-.015,
-.016064,-.015571,
-.015571,-.016064,
-.015,-.016464,
-.014368,-.016759,
-.013695,-.016939,
-.013,-.017,
.013,-.017,
.013695,-.016939,
.014368,-.016759,
.015,-.016464,
.015571,-.016064,
.016064,-.015571,
.016464,-.015,
.016759,-.014368,
.016939,-.013695,
.017,-.013,
.017,.013,
.016939,.013695,
.016759,.014368,
.016464,.015,
.016064,.015571,
.015571,.016064,
.015,.016464,
.014368,.016759,
.013695,.016939,
.013,.017,
-.013,.017,
-.013695,.016939,
-.014368,.016759,
-.015,.016464,
-.015571,.016064,
-.016064,.015571,
-.016464,.015,
-.016759,.014368,
-.016939,.013695,
-.017,.013,
0.0*
%
%ADD15MACRO15*%
%AMMACRO30*
4,1,40,.007,.011,
-.007,.011,
-.007695,.010939,
-.008368,.010759,
-.009,.010464,
-.009571,.010064,
-.010064,.009571,
-.010464,.009,
-.010759,.008368,
-.010939,.007695,
-.011,.007,
-.011,-.007,
-.010939,-.007695,
-.010759,-.008368,
-.010464,-.009,
-.010064,-.009571,
-.009571,-.010064,
-.009,-.010464,
-.008368,-.010759,
-.007695,-.010939,
-.007,-.011,
.007,-.011,
.007695,-.010939,
.008368,-.010759,
.009,-.010464,
.009571,-.010064,
.010064,-.009571,
.010464,-.009,
.010759,-.008368,
.010939,-.007695,
.011,-.007,
.011,.007,
.010939,.007695,
.010759,.008368,
.010464,.009,
.010064,.009571,
.009571,.010064,
.009,.010464,
.008368,.010759,
.007695,.010939,
.007,.011,
0.0*
%
%ADD30MACRO30*%
%AMMACRO21*
4,1,40,.011,-.007,
.011,.007,
.010939,.007695,
.010759,.008368,
.010464,.009,
.010064,.009571,
.009571,.010064,
.009,.010464,
.008368,.010759,
.007695,.010939,
.007,.011,
-.007,.011,
-.007695,.010939,
-.008368,.010759,
-.009,.010464,
-.009571,.010064,
-.010064,.009571,
-.010464,.009,
-.010759,.008368,
-.010939,.007695,
-.011,.007,
-.011,-.007,
-.010939,-.007695,
-.010759,-.008368,
-.010464,-.009,
-.010064,-.009571,
-.009571,-.010064,
-.009,-.010464,
-.008368,-.010759,
-.007695,-.010939,
-.007,-.011,
.007,-.011,
.007695,-.010939,
.008368,-.010759,
.009,-.010464,
.009571,-.010064,
.010064,-.009571,
.010464,-.009,
.010759,-.008368,
.010939,-.007695,
.011,-.007,
0.0*
%
%ADD21MACRO21*%
%AMMACRO136*
4,1,20,.0635,-.1075,
.049,-.1075,
.049,-.118,
.0395,-.118,
.0395,-.1075,
-.0395,-.1075,
-.0395,-.118,
-.049,-.118,
-.049,-.1075,
-.0635,-.1075,
-.0635,.1075,
-.049,.1075,
-.049,.118,
-.0395,.118,
-.0395,.1075,
.0395,.1075,
.0395,.118,
.049,.118,
.049,.1075,
.0635,.1075,
.0635,-.1075,
0.0*
%
%ADD136MACRO136*%
%AMMACRO19*
4,1,40,-.012,.008,
-.012,-.008,
-.011939,-.008695,
-.011759,-.009368,
-.011464,-.01,
-.011064,-.010571,
-.010571,-.011064,
-.01,-.011464,
-.009368,-.011759,
-.008695,-.011939,
-.008,-.012,
.008,-.012,
.008695,-.011939,
.009368,-.011759,
.01,-.011464,
.010571,-.011064,
.011064,-.010571,
.011464,-.01,
.011759,-.009368,
.011939,-.008695,
.012,-.008,
.012,.008,
.011939,.008695,
.011759,.009368,
.011464,.01,
.011064,.010571,
.010571,.011064,
.01,.011464,
.009368,.011759,
.008695,.011939,
.008,.012,
-.008,.012,
-.008695,.011939,
-.009368,.011759,
-.01,.011464,
-.010571,.011064,
-.011064,.010571,
-.011464,.01,
-.011759,.009368,
-.011939,.008695,
-.012,.008,
0.0*
%
%ADD19MACRO19*%
%AMMACRO11*
4,1,40,.008,.012,
-.008,.012,
-.008695,.011939,
-.009368,.011759,
-.01,.011464,
-.010571,.011064,
-.011064,.010571,
-.011464,.01,
-.011759,.009368,
-.011939,.008695,
-.012,.008,
-.012,-.008,
-.011939,-.008695,
-.011759,-.009368,
-.011464,-.01,
-.011064,-.010571,
-.010571,-.011064,
-.01,-.011464,
-.009368,-.011759,
-.008695,-.011939,
-.008,-.012,
.008,-.012,
.008695,-.011939,
.009368,-.011759,
.01,-.011464,
.010571,-.011064,
.011064,-.010571,
.011464,-.01,
.011759,-.009368,
.011939,-.008695,
.012,-.008,
.012,.008,
.011939,.008695,
.011759,.009368,
.011464,.01,
.011064,.010571,
.010571,.011064,
.01,.011464,
.009368,.011759,
.008695,.011939,
.008,.012,
0.0*
%
%ADD11MACRO11*%
%AMMACRO37*
4,1,40,-.013,-.017,
.013,-.017,
.013695,-.016939,
.014368,-.016759,
.015,-.016464,
.015571,-.016064,
.016064,-.015571,
.016464,-.015,
.016759,-.014368,
.016939,-.013695,
.017,-.013,
.017,.013,
.016939,.013695,
.016759,.014368,
.016464,.015,
.016064,.015571,
.015571,.016064,
.015,.016464,
.014368,.016759,
.013695,.016939,
.013,.017,
-.013,.017,
-.013695,.016939,
-.014368,.016759,
-.015,.016464,
-.015571,.016064,
-.016064,.015571,
-.016464,.015,
-.016759,.014368,
-.016939,.013695,
-.017,.013,
-.017,-.013,
-.016939,-.013695,
-.016759,-.014368,
-.016464,-.015,
-.016064,-.015571,
-.015571,-.016064,
-.015,-.016464,
-.014368,-.016759,
-.013695,-.016939,
-.013,-.017,
0.0*
%
%ADD37MACRO37*%
%AMMACRO14*
4,1,40,-.017,.013,
-.017,-.013,
-.016939,-.013695,
-.016759,-.014368,
-.016464,-.015,
-.016064,-.015571,
-.015571,-.016064,
-.015,-.016464,
-.014368,-.016759,
-.013695,-.016939,
-.013,-.017,
.013,-.017,
.013695,-.016939,
.014368,-.016759,
.015,-.016464,
.015571,-.016064,
.016064,-.015571,
.016464,-.015,
.016759,-.014368,
.016939,-.013695,
.017,-.013,
.017,.013,
.016939,.013695,
.016759,.014368,
.016464,.015,
.016064,.015571,
.015571,.016064,
.015,.016464,
.014368,.016759,
.013695,.016939,
.013,.017,
-.013,.017,
-.013695,.016939,
-.014368,.016759,
-.015,.016464,
-.015571,.016064,
-.016064,.015571,
-.016464,.015,
-.016759,.014368,
-.016939,.013695,
-.017,.013,
0.0*
%
%ADD14MACRO14*%
%ADD132R,.135X.21*%
%ADD67R,.012X.022*%
%ADD118R,.041X.012*%
%ADD116R,.012X.041*%
%AMMACRO111*
4,1,3,-.025,-.0125,
0.0,.0125,
.025,-.0125,
-.025,-.0125,
0.0*
%
%ADD111MACRO111*%
%ADD27R,.04X.022*%
%ADD104R,.06X.012*%
%AMMACRO95*
4,1,3,0.0,.0125,
.025,-.0125,
-.025,-.0125,
0.0,.0125,
0.0*
%
%ADD95MACRO95*%
%ADD78R,.02X.06*%
%ADD45R,.022X.04*%
%ADD70R,.023X.04*%
%ADD52R,.012X.042*%
%ADD50R,.042X.012*%
%ADD96R,.044X.012*%
%ADD91R,.06X.014*%
%ADD90R,.04X.016*%
%ADD102R,.014X.06*%
%ADD100R,.105X.128*%
%ADD48R,.016X.04*%
%ADD41R,.012X.036*%
%ADD40R,.036X.012*%
%ADD120R,.041X.053*%
%ADD117R,.037X.012*%
%ADD115R,.012X.037*%
%ADD85R,.06X.016*%
%ADD68R,.03X.045*%
%ADD51R,.012X.036*%
%ADD49R,.036X.012*%
%ADD42R,.012X.046*%
%ADD39R,.046X.012*%
%ADD133R,.028X.03*%
%ADD84R,.012X.038*%
%ADD83R,.038X.012*%
%ADD74R,.03X.064*%
%ADD73R,.016X.06*%
%ADD97R,.02X.066*%
%ADD113R,.042X.055*%
%ADD89R,.05X.065*%
%ADD81R,.104X.187*%
%ADD124R,.037X.042*%
%ADD87R,.02X.059*%
%ADD65R,.065X.05*%
%ADD125R,.044X.028*%
%ADD98R,.065X.025*%
%ADD86R,.036X.026*%
%ADD131R,.028X.044*%
%ADD75R,.09X.045*%
%ADD62R,.048X.016*%
%ADD61R,.036X.055*%
%ADD47R,.045X.055*%
%ADD44R,.025X.065*%
%ADD59R,.016X.048*%
%ADD53R,.13X.13*%
%ADD22R,.055X.045*%
%ADD108R,.054X.074*%
%ADD80R,.047X.073*%
%ADD79R,.075X.045*%
%ADD77R,.09X.095*%
%ADD76R,.059X.045*%
%ADD55R,.024X.079*%
%ADD18R,.075X.065*%
%AMMACRO105*
4,1,40,-.0225,.007,
-.022378,.008389,
-.022018,.009736,
-.021428,.011,
-.020628,.012142,
-.019642,.013128,
-.0185,.013928,
-.017236,.014518,
-.015889,.014878,
-.0145,.015,
.0145,.015,
.015889,.014878,
.017236,.014518,
.0185,.013928,
.019642,.013128,
.020628,.012142,
.021428,.011,
.022018,.009736,
.022378,.008389,
.0225,.007,
.0225,-.007,
.022378,-.008389,
.022018,-.009736,
.021428,-.011,
.020628,-.012142,
.019642,-.013128,
.0185,-.013928,
.017236,-.014518,
.015889,-.014878,
.0145,-.015,
-.0145,-.015,
-.015889,-.014878,
-.017236,-.014518,
-.0185,-.013928,
-.019642,-.013128,
-.020628,-.012142,
-.021428,-.011,
-.022018,-.009736,
-.022378,-.008389,
-.0225,-.007,
-.0225,.007,
0.0*
%
%ADD105MACRO105*%
%ADD103R,.095X.09*%
%AMMACRO57*
4,1,40,.007,.0225,
.008389,.022378,
.009736,.022018,
.011,.021428,
.012142,.020628,
.013128,.019642,
.013928,.0185,
.014518,.017236,
.014878,.015889,
.015,.0145,
.015,-.0145,
.014878,-.015889,
.014518,-.017236,
.013928,-.0185,
.013128,-.019642,
.012142,-.020628,
.011,-.021428,
.009736,-.022018,
.008389,-.022378,
.007,-.0225,
-.007,-.0225,
-.008389,-.022378,
-.009736,-.022018,
-.011,-.021428,
-.012142,-.020628,
-.013128,-.019642,
-.013928,-.0185,
-.014518,-.017236,
-.014878,-.015889,
-.015,-.0145,
-.015,.0145,
-.014878,.015889,
-.014518,.017236,
-.013928,.0185,
-.013128,.019642,
-.012142,.020628,
-.011,.021428,
-.009736,.022018,
-.008389,.022378,
-.007,.0225,
.007,.0225,
0.0*
%
%ADD57MACRO57*%
%ADD134R,.057X.039*%
%ADD107R,.069X.055*%
%AMMACRO135*
4,1,40,.024,.012,
.024,-.012,
.023878,-.013389,
.023518,-.014736,
.022928,-.016,
.022128,-.017142,
.021142,-.018128,
.02,-.018928,
.018736,-.019518,
.017389,-.019878,
.016,-.02,
-.016,-.02,
-.017389,-.019878,
-.018736,-.019518,
-.02,-.018928,
-.021142,-.018128,
-.022128,-.017142,
-.022928,-.016,
-.023518,-.014736,
-.023878,-.013389,
-.024,-.012,
-.024,.012,
-.023878,.013389,
-.023518,.014736,
-.022928,.016,
-.022128,.017142,
-.021142,.018128,
-.02,.018928,
-.018736,.019518,
-.017389,.019878,
-.016,.02,
.016,.02,
.017389,.019878,
.018736,.019518,
.02,.018928,
.021142,.018128,
.022128,.017142,
.022928,.016,
.023518,.014736,
.023878,.013389,
.024,.012,
0.0*
%
%ADD135MACRO135*%
%AMMACRO130*
4,1,40,.012,-.024,
-.012,-.024,
-.013389,-.023878,
-.014736,-.023518,
-.016,-.022928,
-.017142,-.022128,
-.018128,-.021142,
-.018928,-.02,
-.019518,-.018736,
-.019878,-.017389,
-.02,-.016,
-.02,.016,
-.019878,.017389,
-.019518,.018736,
-.018928,.02,
-.018128,.021142,
-.017142,.022128,
-.016,.022928,
-.014736,.023518,
-.013389,.023878,
-.012,.024,
.012,.024,
.013389,.023878,
.014736,.023518,
.016,.022928,
.017142,.022128,
.018128,.021142,
.018928,.02,
.019518,.018736,
.019878,.017389,
.02,.016,
.02,-.016,
.019878,-.017389,
.019518,-.018736,
.018928,-.02,
.018128,-.021142,
.017142,-.022128,
.016,-.022928,
.014736,-.023518,
.013389,-.023878,
.012,-.024,
0.0*
%
%ADD130MACRO130*%
%AMMACRO99*
4,1,20,-.032,.047,
-.0155,.047,
-.0155,.074,
-.0045,.074,
-.0045,.049,
.0045,.049,
.0045,.074,
.0155,.074,
.0155,.047,
.032,.047,
.032,-.047,
.0155,-.047,
.0155,-.074,
.0045,-.074,
.0045,-.049,
-.0045,-.049,
-.0045,-.074,
-.0155,-.074,
-.0155,-.047,
-.032,-.047,
-.032,.047,
0.0*
%
%ADD99MACRO99*%
%ADD56R,.138X.138*%
%ADD129R,.047X.098*%
%AMMACRO63*
4,1,40,.012,-.008,
.012,.008,
.011939,.008695,
.011759,.009368,
.011464,.01,
.011064,.010571,
.010571,.011064,
.01,.011464,
.009368,.011759,
.008695,.011939,
.008,.012,
-.008,.012,
-.008695,.011939,
-.009368,.011759,
-.01,.011464,
-.010571,.011064,
-.011064,.010571,
-.011464,.01,
-.011759,.009368,
-.011939,.008695,
-.012,.008,
-.012,-.008,
-.011939,-.008695,
-.011759,-.009368,
-.011464,-.01,
-.011064,-.010571,
-.010571,-.011064,
-.01,-.011464,
-.009368,-.011759,
-.008695,-.011939,
-.008,-.012,
.008,-.012,
.008695,-.011939,
.009368,-.011759,
.01,-.011464,
.010571,-.011064,
.011064,-.010571,
.011464,-.01,
.011759,-.009368,
.011939,-.008695,
.012,-.008,
0.0*
%
%ADD63MACRO63*%
%AMMACRO25*
4,1,40,-.007,-.011,
.007,-.011,
.007695,-.010939,
.008368,-.010759,
.009,-.010464,
.009571,-.010064,
.010064,-.009571,
.010464,-.009,
.010759,-.008368,
.010939,-.007695,
.011,-.007,
.011,.007,
.010939,.007695,
.010759,.008368,
.010464,.009,
.010064,.009571,
.009571,.010064,
.009,.010464,
.008368,.010759,
.007695,.010939,
.007,.011,
-.007,.011,
-.007695,.010939,
-.008368,.010759,
-.009,.010464,
-.009571,.010064,
-.010064,.009571,
-.010464,.009,
-.010759,.008368,
-.010939,.007695,
-.011,.007,
-.011,-.007,
-.010939,-.007695,
-.010759,-.008368,
-.010464,-.009,
-.010064,-.009571,
-.009571,-.010064,
-.009,-.010464,
-.008368,-.010759,
-.007695,-.010939,
-.007,-.011,
0.0*
%
%ADD25MACRO25*%
%ADD16R,.089X.096*%
%AMMACRO12*
4,1,40,-.008,-.012,
.008,-.012,
.008695,-.011939,
.009368,-.011759,
.01,-.011464,
.010571,-.011064,
.011064,-.010571,
.011464,-.01,
.011759,-.009368,
.011939,-.008695,
.012,-.008,
.012,.008,
.011939,.008695,
.011759,.009368,
.011464,.01,
.011064,.010571,
.010571,.011064,
.01,.011464,
.009368,.011759,
.008695,.011939,
.008,.012,
-.008,.012,
-.008695,.011939,
-.009368,.011759,
-.01,.011464,
-.010571,.011064,
-.011064,.010571,
-.011464,.01,
-.011759,.009368,
-.011939,.008695,
-.012,.008,
-.012,-.008,
-.011939,-.008695,
-.011759,-.009368,
-.011464,-.01,
-.011064,-.010571,
-.010571,-.011064,
-.01,-.011464,
-.009368,-.011759,
-.008695,-.011939,
-.008,-.012,
0.0*
%
%ADD12MACRO12*%
%AMMACRO31*
4,1,40,-.011,.007,
-.011,-.007,
-.010939,-.007695,
-.010759,-.008368,
-.010464,-.009,
-.010064,-.009571,
-.009571,-.010064,
-.009,-.010464,
-.008368,-.010759,
-.007695,-.010939,
-.007,-.011,
.007,-.011,
.007695,-.010939,
.008368,-.010759,
.009,-.010464,
.009571,-.010064,
.010064,-.009571,
.010464,-.009,
.010759,-.008368,
.010939,-.007695,
.011,-.007,
.011,.007,
.010939,.007695,
.010759,.008368,
.010464,.009,
.010064,.009571,
.009571,.010064,
.009,.010464,
.008368,.010759,
.007695,.010939,
.007,.011,
-.007,.011,
-.007695,.010939,
-.008368,.010759,
-.009,.010464,
-.009571,.010064,
-.010064,.009571,
-.010464,.009,
-.010759,.008368,
-.010939,.007695,
-.011,.007,
0.0*
%
%ADD31MACRO31*%
%AMMACRO34*
4,1,40,.013,.017,
-.013,.017,
-.013695,.016939,
-.014368,.016759,
-.015,.016464,
-.015571,.016064,
-.016064,.015571,
-.016464,.015,
-.016759,.014368,
-.016939,.013695,
-.017,.013,
-.017,-.013,
-.016939,-.013695,
-.016759,-.014368,
-.016464,-.015,
-.016064,-.015571,
-.015571,-.016064,
-.015,-.016464,
-.014368,-.016759,
-.013695,-.016939,
-.013,-.017,
.013,-.017,
.013695,-.016939,
.014368,-.016759,
.015,-.016464,
.015571,-.016064,
.016064,-.015571,
.016464,-.015,
.016759,-.014368,
.016939,-.013695,
.017,-.013,
.017,.013,
.016939,.013695,
.016759,.014368,
.016464,.015,
.016064,.015571,
.015571,.016064,
.015,.016464,
.014368,.016759,
.013695,.016939,
.013,.017,
0.0*
%
%ADD34MACRO34*%
%AMMACRO24*
4,1,40,.017,-.013,
.017,.013,
.016939,.013695,
.016759,.014368,
.016464,.015,
.016064,.015571,
.015571,.016064,
.015,.016464,
.014368,.016759,
.013695,.016939,
.013,.017,
-.013,.017,
-.013695,.016939,
-.014368,.016759,
-.015,.016464,
-.015571,.016064,
-.016064,.015571,
-.016464,.015,
-.016759,.014368,
-.016939,.013695,
-.017,.013,
-.017,-.013,
-.016939,-.013695,
-.016759,-.014368,
-.016464,-.015,
-.016064,-.015571,
-.015571,-.016064,
-.015,-.016464,
-.014368,-.016759,
-.013695,-.016939,
-.013,-.017,
.013,-.017,
.013695,-.016939,
.014368,-.016759,
.015,-.016464,
.015571,-.016064,
.016064,-.015571,
.016464,-.015,
.016759,-.014368,
.016939,-.013695,
.017,-.013,
0.0*
%
%ADD24MACRO24*%
%AMMACRO93*
4,1,20,-.0635,.1075,
-.049,.1075,
-.049,.118,
-.0395,.118,
-.0395,.1075,
.0395,.1075,
.0395,.118,
.049,.118,
.049,.1075,
.0635,.1075,
.0635,-.1075,
.049,-.1075,
.049,-.118,
.0395,-.118,
.0395,-.1075,
-.0395,-.1075,
-.0395,-.118,
-.049,-.118,
-.049,-.1075,
-.0635,-.1075,
-.0635,.1075,
0.0*
%
%ADD93MACRO93*%
%AMMACRO64*
4,1,40,.012,-.008,
.012,.008,
.011939,.008695,
.011759,.009368,
.011464,.01,
.011064,.010571,
.010571,.011064,
.01,.011464,
.009368,.011759,
.008695,.011939,
.008,.012,
-.008,.012,
-.008695,.011939,
-.009368,.011759,
-.01,.011464,
-.010571,.011064,
-.011064,.010571,
-.011464,.01,
-.011759,.009368,
-.011939,.008695,
-.012,.008,
-.012,-.008,
-.011939,-.008695,
-.011759,-.009368,
-.011464,-.01,
-.011064,-.010571,
-.010571,-.011064,
-.01,-.011464,
-.009368,-.011759,
-.008695,-.011939,
-.008,-.012,
.008,-.012,
.008695,-.011939,
.009368,-.011759,
.01,-.011464,
.010571,-.011064,
.011064,-.010571,
.011464,-.01,
.011759,-.009368,
.011939,-.008695,
.012,-.008,
0.0*
%
%ADD64MACRO64*%
%AMMACRO54*
4,1,15,-.0275,-.115,
-.0275,.115,
.0275,.115,
.0275,.06339,
.02431,.059697,
.021809,.055506,
.020074,.050945,
.019157,.046151,
.019087,.041272,
.019865,.036454,
.021468,.031844,
.023847,.027583,
.02693,.0238,
.0275,.02323,
.0275,-.115,
-.0275,-.115,
0.0*
%
%ADD54MACRO54*%
%AMMACRO17*
4,1,40,-.007,-.011,
.007,-.011,
.007695,-.010939,
.008368,-.010759,
.009,-.010464,
.009571,-.010064,
.010064,-.009571,
.010464,-.009,
.010759,-.008368,
.010939,-.007695,
.011,-.007,
.011,.007,
.010939,.007695,
.010759,.008368,
.010464,.009,
.010064,.009571,
.009571,.010064,
.009,.010464,
.008368,.010759,
.007695,.010939,
.007,.011,
-.007,.011,
-.007695,.010939,
-.008368,.010759,
-.009,.010464,
-.009571,.010064,
-.010064,.009571,
-.010464,.009,
-.010759,.008368,
-.010939,.007695,
-.011,.007,
-.011,-.007,
-.010939,-.007695,
-.010759,-.008368,
-.010464,-.009,
-.010064,-.009571,
-.009571,-.010064,
-.009,-.010464,
-.008368,-.010759,
-.007695,-.010939,
-.007,-.011,
0.0*
%
%ADD17MACRO17*%
%AMMACRO13*
4,1,40,-.008,-.012,
.008,-.012,
.008695,-.011939,
.009368,-.011759,
.01,-.011464,
.010571,-.011064,
.011064,-.010571,
.011464,-.01,
.011759,-.009368,
.011939,-.008695,
.012,-.008,
.012,.008,
.011939,.008695,
.011759,.009368,
.011464,.01,
.011064,.010571,
.010571,.011064,
.01,.011464,
.009368,.011759,
.008695,.011939,
.008,.012,
-.008,.012,
-.008695,.011939,
-.009368,.011759,
-.01,.011464,
-.010571,.011064,
-.011064,.010571,
-.011464,.01,
-.011759,.009368,
-.011939,.008695,
-.012,.008,
-.012,-.008,
-.011939,-.008695,
-.011759,-.009368,
-.011464,-.01,
-.011064,-.010571,
-.010571,-.011064,
-.01,-.011464,
-.009368,-.011759,
-.008695,-.011939,
-.008,-.012,
0.0*
%
%ADD13MACRO13*%
%AMMACRO32*
4,1,40,-.011,.007,
-.011,-.007,
-.010939,-.007695,
-.010759,-.008368,
-.010464,-.009,
-.010064,-.009571,
-.009571,-.010064,
-.009,-.010464,
-.008368,-.010759,
-.007695,-.010939,
-.007,-.011,
.007,-.011,
.007695,-.010939,
.008368,-.010759,
.009,-.010464,
.009571,-.010064,
.010064,-.009571,
.010464,-.009,
.010759,-.008368,
.010939,-.007695,
.011,-.007,
.011,.007,
.010939,.007695,
.010759,.008368,
.010464,.009,
.010064,.009571,
.009571,.010064,
.009,.010464,
.008368,.010759,
.007695,.010939,
.007,.011,
-.007,.011,
-.007695,.010939,
-.008368,.010759,
-.009,.010464,
-.009571,.010064,
-.010064,.009571,
-.010464,.009,
-.010759,.008368,
-.010939,.007695,
-.011,.007,
0.0*
%
%ADD32MACRO32*%
%ADD137C,.006*%
G75*
%LPD*%
G75*
G36*
G01X112000Y786615D02*
X120550D01*
Y795565D01*
X112000D01*
Y786615D01*
G37*
G36*
G01X100850D02*
X109400D01*
Y795565D01*
X100850D01*
Y786615D01*
G37*
G36*
G01X112000Y798165D02*
X120550D01*
Y807115D01*
X112000D01*
Y798165D01*
G37*
G36*
G01X100850D02*
X109400D01*
Y807115D01*
X100850D01*
Y798165D01*
G37*
G54D100*
X302943Y166500D03*
X281057D03*
X938457Y44100D03*
X960343D03*
G54D110*
X598808Y205137D03*
X602808Y213937D03*
X606808Y205137D03*
G54D101*
X272979Y354640D03*
X291479D03*
G54D120*
X764698Y0D03*
X775460D03*
G54D102*
X298306Y735298D03*
X295746D03*
X293186D03*
X290626D03*
X288066D03*
X285506D03*
X282946D03*
X280386D03*
X277826D03*
Y757498D03*
X280386D03*
X282946D03*
X285506D03*
X288066D03*
X290626D03*
X293186D03*
X295746D03*
X298306D03*
X305986Y735298D03*
X303426D03*
X300866D03*
Y757498D03*
X303426D03*
X305986D03*
X461440Y84600D03*
X464000D03*
X466560D03*
X469120D03*
Y106800D03*
X466560D03*
X464000D03*
X461440D03*
X471680Y84600D03*
X474240D03*
X476800D03*
X479360D03*
Y106800D03*
X476800D03*
X474240D03*
X471680D03*
X491326Y809498D03*
X493886D03*
X496446D03*
X499006D03*
X501566D03*
Y787298D03*
X499006D03*
X496446D03*
X493886D03*
X491326D03*
X504126Y809498D03*
X506686D03*
X509246D03*
X511806D03*
X514366D03*
X516926D03*
X519486D03*
Y787298D03*
X516926D03*
X514366D03*
X511806D03*
X509246D03*
X506686D03*
X504126D03*
X873626Y764298D03*
X871066D03*
X868506D03*
X865946D03*
X863386D03*
X860826D03*
Y786498D03*
X863386D03*
X865946D03*
X868506D03*
X871066D03*
X873626D03*
X891660Y334690D03*
X894220D03*
X896780D03*
X899340D03*
Y318510D03*
X896780D03*
X894220D03*
X891660D03*
X888986Y764298D03*
X886426D03*
X883866D03*
X881306D03*
X878746D03*
X876186D03*
Y786498D03*
X878746D03*
X881306D03*
X883866D03*
X886426D03*
X888986D03*
X1007253Y13707D03*
X1004753D03*
X1002253D03*
X999753D03*
X997253D03*
Y34307D03*
X999753D03*
X1002253D03*
X1004753D03*
X1007253D03*
X1014753Y13707D03*
X1012253D03*
X1009753D03*
Y34307D03*
X1012253D03*
X1014753D03*
X1264820Y377500D03*
X1267380D03*
X1269940D03*
X1272500D03*
X1275060D03*
X1277620D03*
Y355300D03*
X1275060D03*
X1272500D03*
X1269940D03*
X1267380D03*
X1264820D03*
X1280180Y377500D03*
X1282740D03*
X1285300D03*
X1287860D03*
X1290420D03*
X1292980D03*
Y355300D03*
X1290420D03*
X1287860D03*
X1285300D03*
X1282740D03*
X1280180D03*
X1305548Y714967D03*
X1308108D03*
X1310668D03*
Y692767D03*
X1308108D03*
X1305548D03*
X1313228Y714967D03*
X1315788D03*
X1318348D03*
X1320908D03*
X1323468D03*
X1326028D03*
X1328588D03*
X1331148D03*
X1333708D03*
Y692767D03*
X1331148D03*
X1328588D03*
X1326028D03*
X1323468D03*
X1320908D03*
X1318348D03*
X1315788D03*
X1313228D03*
G54D111*
X603363Y221258D03*
G54D130*
X1024330Y26232D03*
X1028330Y35032D03*
X1020330D03*
G54D103*
X320500Y165100D03*
Y189900D03*
X674763Y227208D03*
Y252008D03*
X674837Y266292D03*
Y291092D03*
X1234500Y202100D03*
Y226900D03*
Y260100D03*
Y284900D03*
X1255000Y202100D03*
Y226900D03*
Y260100D03*
Y284900D03*
G54D10*
X22000Y171200D03*
X48400Y269200D03*
X38500Y280800D03*
X47300Y709600D03*
X72300Y261900D03*
X95223Y388904D03*
X68500Y420700D03*
X74000Y561200D03*
X80500Y562700D03*
X84000D03*
X98500Y598200D03*
X81000Y582200D03*
X81500Y634200D03*
X74600Y727500D03*
X104050Y131660D03*
X100900Y177800D03*
X121799Y359964D03*
X108400Y388400D03*
X118351Y574636D03*
X113851D03*
X145809Y574830D03*
X152319Y574920D03*
X159751Y574836D03*
X153700Y732600D03*
X150200D03*
X146500Y787700D03*
X143000D03*
X186000Y708700D03*
X182500D03*
X186000Y764200D03*
X182500D03*
X205200Y196300D03*
X213500Y510200D03*
X209500D03*
X221000Y518200D03*
X246500Y525700D03*
X282300Y499400D03*
X459200Y372500D03*
X462700D03*
X515950Y130260D03*
X519450D03*
X524450D03*
X527950D03*
X532950D03*
X536450D03*
X525409Y320741D03*
X541450Y130260D03*
X544950D03*
X554400Y339300D03*
X600800Y130100D03*
X588000Y130200D03*
X584500D03*
X577730Y130180D03*
X574300D03*
X593000Y130200D03*
X596500D03*
X604300Y130100D03*
X638000Y130200D03*
X634500D03*
X627676D03*
X624176D03*
X609500Y364313D03*
X646000Y130200D03*
X642500D03*
X861752Y14200D03*
X858252D03*
X854500Y45700D03*
X878800Y52800D03*
X1043418Y32166D03*
X1142000Y130200D03*
X1138500D03*
X1161407Y130854D03*
X1157907D03*
X1199500Y130200D03*
X1196000D03*
X1190935Y130248D03*
X1207949Y130130D03*
X1204449D03*
X1187435Y130248D03*
X1178661Y130327D03*
X1182161D03*
X1243000Y130200D03*
X1239500D03*
X1234309Y130312D03*
X1230809D03*
X1225448Y130309D03*
X1221948D03*
X1277365Y130022D03*
X1273865D03*
X1258544Y130119D03*
X1262044D03*
X1296117Y129827D03*
X1292617D03*
X1286643Y129930D03*
X1283143D03*
X1319000Y278700D03*
X1378160Y181001D03*
G54D112*
X603363Y223958D03*
G54D121*
X783300Y1100D03*
X794900D03*
X838300Y2000D03*
X826700D03*
G54D131*
X1056650Y36200D03*
X1049150D03*
X1056650Y28600D03*
G54D113*
X597522Y356988D03*
Y366212D03*
X603478D03*
Y356988D03*
G54D104*
X336141Y323975D03*
Y325945D03*
Y327915D03*
Y329885D03*
X345341D03*
Y327915D03*
Y325945D03*
Y323975D03*
X872850Y-1435D03*
Y530D03*
Y2500D03*
Y4470D03*
Y6435D03*
X889150D03*
Y4470D03*
Y2500D03*
Y530D03*
Y-1435D03*
G54D11*
X22000Y174800D03*
X48400Y272800D03*
X38500Y284400D03*
X47300Y713200D03*
X72300Y265500D03*
X95223Y392504D03*
X68500Y424300D03*
X74000Y564800D03*
X80500Y566300D03*
X84000D03*
X98500Y601800D03*
X81000Y585800D03*
X81500Y637800D03*
X74600Y731100D03*
X104050Y135260D03*
X100900Y181400D03*
X121799Y363564D03*
X108400Y392000D03*
X118351Y578236D03*
X113851D03*
X145809Y578430D03*
X152319Y578520D03*
X159751Y578436D03*
X153700Y736200D03*
X150200D03*
X146500Y791300D03*
X143000D03*
X186000Y712300D03*
X182500D03*
X186000Y767800D03*
X182500D03*
X205200Y199900D03*
X213500Y513800D03*
X209500D03*
X221000Y521800D03*
X246500Y529300D03*
X282300Y503000D03*
X459200Y376100D03*
X462700D03*
X515950Y133860D03*
X519450D03*
X524450D03*
X527950D03*
X532950D03*
X536450D03*
X525409Y324341D03*
X541450Y133860D03*
X544950D03*
X554400Y342900D03*
X600800Y133700D03*
X588000Y133800D03*
X584500D03*
X577730Y133780D03*
X574300D03*
X593000Y133800D03*
X596500D03*
X604300Y133700D03*
X638000Y133800D03*
X634500D03*
X627676D03*
X624176D03*
X609500Y367913D03*
X646000Y133800D03*
X642500D03*
X861752Y17800D03*
X858252D03*
X854500Y49300D03*
X878800Y56400D03*
X1043418Y35766D03*
X1142000Y133800D03*
X1138500D03*
X1161407Y134454D03*
X1157907D03*
X1199500Y133800D03*
X1196000D03*
X1190935Y133848D03*
X1207949Y133730D03*
X1204449D03*
X1187435Y133848D03*
X1178661Y133927D03*
X1182161D03*
X1243000Y133800D03*
X1239500D03*
X1234309Y133912D03*
X1230809D03*
X1225448Y133909D03*
X1221948D03*
X1277365Y133622D03*
X1273865D03*
X1258544Y133719D03*
X1262044D03*
X1296117Y133427D03*
X1292617D03*
X1286643Y133530D03*
X1283143D03*
X1319000Y282300D03*
X1378160Y184601D03*
G54D20*
X27000Y362700D03*
X53000Y207900D03*
X57000D03*
X37650Y212700D03*
X41650D03*
X53422Y357814D03*
X53200Y477700D03*
X64000Y494200D03*
X46900Y493900D03*
X31200Y712600D03*
X57200Y686400D03*
X60800Y766500D03*
X56700D03*
X52300Y766600D03*
X35000Y766800D03*
X39000D03*
X92400Y207300D03*
X88400D03*
X92400Y218700D03*
X77800Y212800D03*
X73800Y224300D03*
X88400Y218700D03*
X73800Y212800D03*
X77800Y224300D03*
X76170Y262620D03*
X96043Y434143D03*
X72500Y424200D03*
X84900Y585700D03*
X66000Y594200D03*
X80950Y705350D03*
X91800Y723100D03*
X74300Y766100D03*
X108050Y135160D03*
X106500Y280600D03*
X108500Y290600D03*
X117761Y372506D03*
X104507Y392134D03*
X127400Y408300D03*
X120252Y443752D03*
X100079Y426717D03*
X116235Y451235D03*
X103500Y461200D03*
X115500D03*
X106900Y728000D03*
X162900Y240990D03*
X146000Y370700D03*
X155700Y409700D03*
X134571Y409796D03*
X135250Y443690D03*
X146200Y461200D03*
X150632Y453555D03*
X146431Y453478D03*
X138769Y578420D03*
X153700Y744100D03*
X164500Y778200D03*
X160000Y816200D03*
X146500Y799200D03*
X186418Y199756D03*
X185500Y574200D03*
X189500D03*
X195500Y601700D03*
X191500Y594200D03*
Y586700D03*
X199500Y737200D03*
X186000Y720200D03*
X184700Y736100D03*
X171700Y723100D03*
X186000Y775700D03*
X167200Y761100D03*
X199500Y792700D03*
X177500Y791200D03*
X225900Y105300D03*
X200300Y199800D03*
X225000Y529200D03*
X229000Y521800D03*
X205500Y574200D03*
X204000Y699200D03*
X217000Y712200D03*
X204000Y754700D03*
X217000Y767700D03*
X240400Y233800D03*
X266729Y357340D03*
X260600Y476500D03*
X242500Y521200D03*
X257500Y529200D03*
X253500Y521200D03*
X237300Y639100D03*
X281500Y137200D03*
X281100Y208500D03*
X278100Y478000D03*
X284200Y474500D03*
X282500Y495200D03*
X274406Y723098D03*
X278406D03*
X286500Y779700D03*
X291000Y772100D03*
X295079Y772050D03*
X299148Y772305D03*
X286500Y772200D03*
X308300Y336000D03*
X301929Y358440D03*
X304000Y779900D03*
X307406Y772098D03*
X311406D03*
X315406D03*
X303300Y772000D03*
X337410Y295860D03*
X461900Y68900D03*
X455800Y98900D03*
Y106400D03*
X466905Y122328D03*
X462868Y122324D03*
X462700Y384000D03*
X470200Y68900D03*
X478400D03*
X480881Y140014D03*
X498903Y168592D03*
X498400Y201900D03*
X480700Y363000D03*
X493700Y376000D03*
X476200Y401000D03*
X487906Y775098D03*
X491906D03*
X500100Y824100D03*
X507700Y171500D03*
X507300Y182400D03*
X531232Y236924D03*
X522899Y236937D03*
X517599D03*
X527131Y236880D03*
X535295Y236958D03*
X524177Y294640D03*
X532921Y294517D03*
X536953Y294760D03*
X520906Y824098D03*
X504406D03*
X524906D03*
X508500Y824100D03*
X512579Y824050D03*
X528906Y824098D03*
X516679Y824050D03*
X532906Y824098D03*
X565690Y133430D03*
X569700D03*
X550400Y165000D03*
X567200Y164700D03*
X554500Y165000D03*
X563100Y164700D03*
X542490Y163801D03*
X575600Y164600D03*
X571400Y164700D03*
X613709Y133281D03*
X617711D03*
X627363Y231808D03*
X628000Y337300D03*
X624000D03*
X632000Y324300D03*
X615100Y365200D03*
X613500Y357083D03*
X632000Y379300D03*
X627500D03*
X636300D03*
X617000Y390300D03*
X627500Y387300D03*
X623000Y390300D03*
X640500Y379300D03*
X724890Y59830D03*
X765300Y107600D03*
X791800Y29300D03*
X781100Y138600D03*
X815500Y20500D03*
X820018Y51079D03*
X824118D03*
X850300Y17700D03*
X867500Y23700D03*
Y16200D03*
X857406Y752098D03*
X861406D03*
X869756Y801098D03*
X873850Y801100D03*
X870900Y808800D03*
X896500Y16700D03*
X886520Y16702D03*
X899200Y65100D03*
X906500Y93200D03*
X893000D03*
X897500D03*
X884000D03*
X879500D03*
X902000D03*
X888500D03*
X875000D03*
X895000Y309300D03*
X891000D03*
X886276Y803748D03*
X890406Y801098D03*
X877949Y803700D03*
X894406Y801098D03*
X882049Y803700D03*
X898406Y801098D03*
X955400Y72400D03*
X951500Y93200D03*
X947000D03*
X942500D03*
X996230Y46444D03*
X1033000Y69700D03*
X1037000Y105200D03*
X1041500D03*
X1024000D03*
X1028000D03*
X1032500D03*
X1020000D03*
X1015948D03*
X1068673Y24345D03*
X1070733Y44623D03*
X1050500Y105200D03*
X1046000D03*
X1173479Y133571D03*
X1169467Y133576D03*
X1216752Y133515D03*
X1212748D03*
X1270005Y133621D03*
X1265997Y133622D03*
X1258500Y342200D03*
X1270500D03*
X1262500D03*
X1266500D03*
X1277500Y401200D03*
Y393700D03*
X1307000Y282200D03*
X1301500Y393700D03*
X1293500D03*
X1297500D03*
X1285500D03*
X1305500D03*
X1289500D03*
X1302128Y680567D03*
X1306128D03*
X1335071Y137811D03*
X1317300Y301600D03*
X1321400D03*
X1315000Y282200D03*
X1313000Y293200D03*
X1314628Y729567D03*
X1326128D03*
X1330128D03*
X1334128D03*
X1338128D03*
X1326100Y737600D03*
X1361500Y270200D03*
G54D122*
X803264Y0D03*
X815634D03*
G54D12*
X21900Y195900D03*
X21800Y184400D03*
X23100Y220500D03*
X31500D03*
X38500Y276800D03*
X41500Y265300D03*
X43900Y303500D03*
X54600Y325200D03*
X61799Y376157D03*
X42900Y766800D03*
X67600Y330900D03*
X84700Y331800D03*
X81300D03*
X74000Y575800D03*
X84000Y574300D03*
X80500D03*
X100900Y194200D03*
X130051Y651946D03*
X133299Y578520D03*
X190520Y838101D03*
X194520D03*
X222500Y513800D03*
X226000D03*
X221000Y529300D03*
X207118Y838101D03*
X203118D03*
X219717D03*
X215717D03*
X232315D03*
X228315D03*
X239600Y149700D03*
X244300Y233800D03*
X246500Y521300D03*
X259857Y513748D03*
X241300Y639200D03*
X266906Y772198D03*
X254362Y838101D03*
X250362D03*
X266961D03*
X262961D03*
X267300Y296800D03*
X297729Y358440D03*
X279559Y838101D03*
X275559D03*
X329241Y328730D03*
X301500Y487100D03*
X313354Y838101D03*
X317354D03*
X329953D03*
X325953D03*
X367748D03*
X363748D03*
X342551D03*
X338551D03*
X351150D03*
X355150D03*
X389796D03*
X385796D03*
X398394D03*
X402394D03*
X410993D03*
X414993D03*
X423591D03*
X427591D03*
X459071Y122341D03*
X480406Y824198D03*
X505477Y295540D03*
X525409Y332341D03*
X542120Y218605D03*
X544851Y838101D03*
X548851D03*
X557449D03*
X561449D03*
X570048D03*
X604170Y334140D03*
X574048Y838101D03*
X586646D03*
X582646D03*
X599245D03*
X595245D03*
X619363Y231908D03*
X609500Y357183D03*
X611843Y838101D03*
X607843D03*
X624442D03*
X620442D03*
X637040D03*
X633040D03*
X659087D03*
X655087D03*
X671685D03*
X667685D03*
X684284D03*
X680284D03*
X696882D03*
X692882D03*
X724379D03*
X728379D03*
X736977D03*
X740977D03*
X749576D03*
X753576D03*
X762174D03*
X766174D03*
X774772D03*
X778772D03*
X787370D03*
X791370D03*
X799969D03*
X803969D03*
X812567D03*
X816567D03*
X837764D03*
X849906Y801198D03*
X841764Y838101D03*
X850362D03*
X854362D03*
X896000Y6300D03*
X900522Y16766D03*
X905500Y334800D03*
X1039675Y18887D03*
X1014451Y45106D03*
X1040914Y838101D03*
X1044914D03*
X1053512D03*
X1057512D03*
X1066111D03*
X1070111D03*
X1091307D03*
X1095307D03*
X1103906D03*
X1107906D03*
X1078709D03*
X1082709D03*
X1120504D03*
X1116504D03*
X1129103D03*
X1133103D03*
X1141701D03*
X1145701D03*
X1154299D03*
X1158299D03*
X1176347D03*
X1180347D03*
X1192945D03*
X1188945D03*
X1224441D03*
X1220441D03*
X1237040D03*
X1233040D03*
X1257500Y393800D03*
X1254000D03*
X1249638Y838101D03*
X1245638D03*
X1258237D03*
X1262237D03*
X1274835D03*
X1270835D03*
X1294628Y729667D03*
X1287433Y838101D03*
X1283433D03*
X1312630D03*
X1308630D03*
X1325229D03*
X1321229D03*
X1337827D03*
X1333827D03*
X1346425D03*
X1350425D03*
G54D105*
X478719Y308208D03*
X486219Y312083D03*
X478719Y315958D03*
X733382Y3881D03*
Y-3869D03*
X740882Y6D03*
X873250Y22375D03*
Y14625D03*
X880750Y18500D03*
X1306970Y139185D03*
Y131435D03*
X1314470Y135310D03*
G54D132*
X1273486Y243500D03*
X1314514D03*
G54D21*
X27000Y359300D03*
X37650Y209300D03*
X53000Y204500D03*
X41650Y209300D03*
X57000Y204500D03*
X53422Y354414D03*
X53200Y474300D03*
X64000Y490800D03*
X46900Y490500D03*
X31200Y709200D03*
X57200Y683000D03*
X60800Y763100D03*
X56700D03*
X52300Y763200D03*
X35000Y763400D03*
X39000D03*
X92400Y203900D03*
X88400D03*
X77800Y209400D03*
X73800D03*
X92400Y215300D03*
X73800Y220900D03*
X88400Y215300D03*
X77800Y220900D03*
X76170Y259220D03*
X96043Y430743D03*
X72500Y420800D03*
X84900Y582300D03*
X66000Y590800D03*
X80950Y701950D03*
X91800Y719700D03*
X74300Y762700D03*
X108050Y131760D03*
X106500Y277200D03*
X108500Y287200D03*
X117761Y369106D03*
X104507Y388734D03*
X127400Y404900D03*
X120252Y440352D03*
X100079Y423317D03*
X116235Y447835D03*
X103500Y457800D03*
X115500D03*
X106900Y724600D03*
X162900Y237590D03*
X146000Y367300D03*
X155700Y406300D03*
X134571Y406396D03*
X135250Y440290D03*
X146200Y457800D03*
X150632Y450155D03*
X146431Y450078D03*
X138769Y575020D03*
X153700Y740700D03*
X164500Y774800D03*
X160000Y812800D03*
X146500Y795800D03*
X186418Y196356D03*
X185500Y570800D03*
X189500D03*
X195500Y598300D03*
X191500Y590800D03*
Y583300D03*
X199500Y733800D03*
X186000Y716800D03*
X184700Y732700D03*
X171700Y719700D03*
X186000Y772300D03*
X167200Y757700D03*
X199500Y789300D03*
X177500Y787800D03*
X225900Y101900D03*
X200300Y196400D03*
X225000Y525800D03*
X229000Y518400D03*
X205500Y570800D03*
X204000Y695800D03*
X217000Y708800D03*
X204000Y751300D03*
X217000Y764300D03*
X240400Y230400D03*
X266729Y353940D03*
X260600Y473100D03*
X242500Y517800D03*
X257500Y525800D03*
X253500Y517800D03*
X237300Y635700D03*
X281500Y133800D03*
X281100Y205100D03*
X278100Y474600D03*
X284200Y471100D03*
X282500Y491800D03*
X274406Y719698D03*
X278406D03*
X286500Y776300D03*
X291000Y768700D03*
X295079Y768650D03*
X299148Y768905D03*
X286500Y768800D03*
X308300Y332600D03*
X301929Y355040D03*
X304000Y776500D03*
X307406Y768698D03*
X311406D03*
X315406D03*
X303300Y768600D03*
X337410Y292460D03*
X461900Y65500D03*
X455800Y95500D03*
Y103000D03*
X466905Y118928D03*
X462868Y118924D03*
X462700Y380600D03*
X470200Y65500D03*
X478400D03*
X480881Y136614D03*
X498903Y165192D03*
X498400Y198500D03*
X480700Y359600D03*
X493700Y372600D03*
X476200Y397600D03*
X487906Y771698D03*
X491906D03*
X500100Y820700D03*
X507700Y168100D03*
X507300Y179000D03*
X531232Y233524D03*
X522899Y233537D03*
X517599D03*
X527131Y233480D03*
X535295Y233558D03*
X524177Y291240D03*
X532921Y291117D03*
X536953Y291360D03*
X520906Y820698D03*
X504406D03*
X524906D03*
X508500Y820700D03*
X512579Y820650D03*
X528906Y820698D03*
X516679Y820650D03*
X532906Y820698D03*
X565690Y130030D03*
X569700D03*
X550400Y161600D03*
X567200Y161300D03*
X554500Y161600D03*
X563100Y161300D03*
X542490Y160401D03*
X575600Y161200D03*
X571400Y161300D03*
X613709Y129881D03*
X617711D03*
X627363Y228408D03*
X628000Y333900D03*
X624000D03*
X632000Y320900D03*
X615100Y361800D03*
X632000Y375900D03*
X613500Y353683D03*
X627500Y375900D03*
X636300D03*
X617000Y386900D03*
X627500Y383900D03*
X623000Y386900D03*
X640500Y375900D03*
X724890Y56430D03*
X765300Y104200D03*
X791800Y25900D03*
X781100Y135200D03*
X815500Y17100D03*
X820018Y47679D03*
X824118D03*
X850300Y14300D03*
X867500Y20300D03*
Y12800D03*
X857406Y748698D03*
X861406D03*
X869756Y797698D03*
X873850Y797700D03*
X870900Y805400D03*
X896500Y13300D03*
X886520Y13302D03*
X899200Y61700D03*
X906500Y89800D03*
X893000D03*
X897500D03*
X884000D03*
X879500D03*
X902000D03*
X888500D03*
X875000D03*
X895000Y305900D03*
X891000D03*
X886276Y800348D03*
X890406Y797698D03*
X877949Y800300D03*
X894406Y797698D03*
X882049Y800300D03*
X898406Y797698D03*
X955400Y69000D03*
X951500Y89800D03*
X947000D03*
X942500D03*
X996230Y43044D03*
X1033000Y66300D03*
X1037000Y101800D03*
X1041500D03*
X1024000D03*
X1028000D03*
X1032500D03*
X1020000D03*
X1015948D03*
X1070733Y41223D03*
X1068673Y20945D03*
X1050500Y101800D03*
X1046000D03*
X1173479Y130171D03*
X1169467Y130176D03*
X1216752Y130115D03*
X1212748D03*
X1270005Y130221D03*
X1265997Y130222D03*
X1258500Y338800D03*
X1270500D03*
X1262500D03*
X1266500D03*
X1277500Y397800D03*
Y390300D03*
X1307000Y278800D03*
X1301500Y390300D03*
X1293500D03*
X1297500D03*
X1285500D03*
X1305500D03*
X1289500D03*
X1302128Y677167D03*
X1306128D03*
X1335071Y134411D03*
X1317300Y298200D03*
X1321400D03*
X1315000Y278800D03*
X1313000Y289800D03*
X1314628Y726167D03*
X1326128D03*
X1330128D03*
X1334128D03*
X1338128D03*
X1326100Y734200D03*
X1361500Y266800D03*
G54D30*
X28500Y746900D03*
Y733400D03*
Y729400D03*
X45700Y276800D03*
Y280900D03*
X39100Y394100D03*
X59200Y483000D03*
Y502000D03*
X58800Y708900D03*
X56600Y770800D03*
X70543Y354737D03*
X74200Y506500D03*
Y510500D03*
Y514500D03*
X84400Y529300D03*
X70340Y527270D03*
X84200Y542300D03*
Y546300D03*
X84100Y550400D03*
X84200Y554500D03*
Y558500D03*
X77200Y586000D03*
X90200Y642000D03*
Y646000D03*
X98400Y681900D03*
X81800Y731300D03*
Y727300D03*
X83000Y740900D03*
Y744900D03*
Y766900D03*
X101200Y276300D03*
X104200Y298900D03*
Y302900D03*
X115700Y388600D03*
X115634Y441150D03*
X101700Y569500D03*
X110700Y561500D03*
Y565500D03*
X101700Y592500D03*
X105900Y681900D03*
X119600Y714300D03*
X102600Y727800D03*
X121700Y775000D03*
X153014Y322277D03*
X145513Y322350D03*
X136214Y373985D03*
X160800Y379200D03*
X146698Y420306D03*
X140600Y732300D03*
X132400Y745200D03*
X172484Y186686D03*
Y181686D03*
X197400Y251100D03*
X194015Y289501D03*
X182554Y446672D03*
X174900Y753400D03*
X167700Y808500D03*
X203960Y289306D03*
X213438Y425645D03*
X213238Y441945D03*
X209400Y446000D03*
X213200Y465000D03*
Y469000D03*
Y482000D03*
Y486000D03*
X213300Y494400D03*
X213200Y490000D03*
Y525500D03*
Y521500D03*
Y554500D03*
X226070Y568020D03*
X207200Y729500D03*
Y785000D03*
X239700Y139500D03*
X253928Y124804D03*
X256600Y438600D03*
X259300Y422500D03*
X253400Y443300D03*
X255720Y581381D03*
X233700Y586000D03*
Y590000D03*
X273200Y126000D03*
X272800Y467300D03*
Y485800D03*
X278000Y638900D03*
X285500Y643900D03*
X314700Y221900D03*
X319100Y542500D03*
X338600Y222000D03*
X338300Y335500D03*
X348000Y318500D03*
X463549Y210989D03*
X500232Y130548D03*
X484209Y339041D03*
Y334041D03*
X483900Y393300D03*
X530000Y165815D03*
Y157715D03*
Y161815D03*
X519109Y202072D03*
X511409Y202172D03*
X525800Y340500D03*
X561670Y136909D03*
X554200Y137597D03*
X561731Y334980D03*
X593163Y215308D03*
X575800Y238400D03*
X623063Y217608D03*
X615563Y213608D03*
X608400Y344200D03*
X667200Y212000D03*
X692600Y212200D03*
X681200Y212000D03*
X725913Y2380D03*
X736463Y31882D03*
X720705Y14964D03*
X724359Y28613D03*
X738330Y63910D03*
X717700Y64000D03*
X716810Y55860D03*
Y51796D03*
X756000Y53800D03*
X761150Y75900D03*
X761300Y86500D03*
Y90600D03*
Y102900D03*
Y82300D03*
X768900Y121200D03*
Y133500D03*
X759200Y118800D03*
X778300Y74000D03*
X798300Y74200D03*
X838800Y105600D03*
X810200Y86500D03*
Y90600D03*
X812113Y118898D03*
X849581Y5499D03*
X865200Y32000D03*
Y40000D03*
X865700Y52800D03*
Y48500D03*
X903700Y358500D03*
Y350000D03*
Y345600D03*
X889870Y808230D03*
X908200Y37000D03*
X932300Y78600D03*
X958781Y64624D03*
X992411Y14160D03*
X992569Y27248D03*
Y23121D03*
X1024760Y2024D03*
X1036816Y33563D03*
X1035592Y11076D03*
X1054700Y22200D03*
X1043367Y11296D03*
X1058200Y48700D03*
X1052800Y64100D03*
X1079259Y5500D03*
Y500D03*
X1079269Y22450D03*
X1079824Y39554D03*
X1079269Y26950D03*
X1079824Y35054D03*
X1078539Y14070D03*
X1123700Y235000D03*
X1137700Y234500D03*
X1152200D03*
X1292700Y300000D03*
X1318700Y274500D03*
X1360200Y278500D03*
G54D114*
X624934Y257608D03*
X656592D03*
G54D123*
X831592Y29400D03*
X833167D03*
X834742D03*
X836317D03*
X837892D03*
X839467D03*
Y51600D03*
X837892D03*
X836317D03*
X834742D03*
X833167D03*
X831592D03*
X841037Y29400D03*
X842612D03*
X844187D03*
X845762D03*
X847337D03*
X848912D03*
Y51600D03*
X847337D03*
X845762D03*
X844187D03*
X842612D03*
X841037D03*
G54D13*
X21900Y192300D03*
X21800Y180800D03*
X23100Y216900D03*
X31500D03*
X38500Y273200D03*
X41500Y261700D03*
X43900Y299900D03*
X54600Y321600D03*
X61799Y372557D03*
X42900Y763200D03*
X67600Y327300D03*
X84700Y328200D03*
X81300D03*
X74000Y572200D03*
X84000Y570700D03*
X80500D03*
X100900Y190600D03*
X130051Y648346D03*
X133299Y574920D03*
X190520Y834501D03*
X194520D03*
X222500Y510200D03*
X226000D03*
X221000Y525700D03*
X207118Y834501D03*
X203118D03*
X219717D03*
X215717D03*
X232315D03*
X228315D03*
X239600Y146100D03*
X244300Y230200D03*
X259857Y510148D03*
X246500Y517700D03*
X241300Y635600D03*
X266906Y768598D03*
X254362Y834501D03*
X250362D03*
X266961D03*
X262961D03*
X267300Y293200D03*
X297729Y354840D03*
X279559Y834501D03*
X275559D03*
X329241Y325130D03*
X301500Y483500D03*
X313354Y834501D03*
X317354D03*
X329953D03*
X325953D03*
X367748D03*
X363748D03*
X342551D03*
X338551D03*
X351150D03*
X355150D03*
X389796D03*
X385796D03*
X398394D03*
X402394D03*
X410993D03*
X414993D03*
X423591D03*
X427591D03*
X459071Y118741D03*
X480406Y820598D03*
X505477Y291940D03*
X525409Y328741D03*
X542120Y215005D03*
X544851Y834501D03*
X548851D03*
X557449D03*
X561449D03*
X570048D03*
X604170Y330540D03*
X574048Y834501D03*
X586646D03*
X582646D03*
X599245D03*
X595245D03*
X619363Y228308D03*
X609500Y353583D03*
X611843Y834501D03*
X607843D03*
X624442D03*
X620442D03*
X637040D03*
X633040D03*
X659087D03*
X655087D03*
X671685D03*
X667685D03*
X684284D03*
X680284D03*
X696882D03*
X692882D03*
X724379D03*
X728379D03*
X736977D03*
X740977D03*
X749576D03*
X753576D03*
X762174D03*
X766174D03*
X774772D03*
X778772D03*
X787370D03*
X791370D03*
X799969D03*
X803969D03*
X812567D03*
X816567D03*
X837764D03*
X849906Y797598D03*
X841764Y834501D03*
X850362D03*
X854362D03*
X896000Y2700D03*
X900522Y13166D03*
X905500Y331200D03*
X1039675Y15287D03*
X1014451Y41506D03*
X1040914Y834501D03*
X1044914D03*
X1053512D03*
X1057512D03*
X1066111D03*
X1070111D03*
X1091307D03*
X1095307D03*
X1103906D03*
X1107906D03*
X1078709D03*
X1082709D03*
X1120504D03*
X1116504D03*
X1129103D03*
X1133103D03*
X1141701D03*
X1145701D03*
X1154299D03*
X1158299D03*
X1176347D03*
X1180347D03*
X1192945D03*
X1188945D03*
X1224441D03*
X1220441D03*
X1237040D03*
X1233040D03*
X1257500Y390200D03*
X1254000D03*
X1249638Y834501D03*
X1245638D03*
X1258237D03*
X1262237D03*
X1274835D03*
X1270835D03*
X1294628Y726067D03*
X1287433Y834501D03*
X1283433D03*
X1312630D03*
X1308630D03*
X1325229D03*
X1321229D03*
X1337827D03*
X1333827D03*
X1346425D03*
X1350425D03*
G54D31*
X25300Y739200D03*
X58300Y327500D03*
X62800Y327200D03*
X64500Y420800D03*
X32000Y473300D03*
X49000D03*
X53200Y466700D03*
X55261Y507441D03*
X51300Y709700D03*
X43300D03*
X57200Y690600D03*
X80300Y259200D03*
X95670Y340811D03*
X91600Y340700D03*
X70591Y363199D03*
X70654Y370860D03*
X80000Y403500D03*
X84274Y399141D03*
X96046Y423330D03*
X92500Y469800D03*
X96700Y469700D03*
X88000Y606900D03*
X72000Y606300D03*
X76000D03*
X66000Y598300D03*
X97500Y631800D03*
X65000Y763100D03*
X108500Y294700D03*
X128180Y311014D03*
X103998Y340850D03*
X99887Y340875D03*
X103617Y332815D03*
X100200Y384900D03*
X100076Y430730D03*
X111500Y457800D03*
X107500D03*
X106900Y732100D03*
X126000Y777300D03*
X151600Y406300D03*
X133000Y457800D03*
X137000D03*
X142000Y453300D03*
X160000Y774800D03*
X164500Y812800D03*
X196018Y196356D03*
X191018D03*
X197841Y430442D03*
X184116Y458610D03*
X192733Y458132D03*
X188150Y458505D03*
X172800Y457800D03*
X197500Y570332D03*
X191500Y598300D03*
X195500Y590800D03*
Y583300D03*
X199500Y695800D03*
X167200Y719700D03*
X199500Y751300D03*
X171700Y757700D03*
X224900Y109400D03*
X224600Y120100D03*
X207369Y147784D03*
X220969Y434972D03*
X209400Y450100D03*
X213500D03*
X225000Y518400D03*
X229000Y525800D03*
X201500Y570332D03*
X226200Y572462D03*
X204000Y733800D03*
Y789300D03*
X261200Y101900D03*
X235505Y144662D03*
X236331Y230380D03*
X258900Y293600D03*
X263000Y293400D03*
X266729Y345940D03*
X244900Y430900D03*
X262900Y430400D03*
X257500Y447538D03*
X253400Y447500D03*
X242500Y525800D03*
X253500D03*
X258000Y517800D03*
X245300Y635700D03*
X277500Y133800D03*
X272900Y293300D03*
X299639Y332701D03*
X294406Y719698D03*
X290406D03*
X286406D03*
X282406D03*
X298406D03*
X278406Y768698D03*
X274406D03*
X282478Y768731D03*
X316646Y293575D03*
X302700Y294562D03*
X320662Y293590D03*
X315300Y337300D03*
X310406Y719698D03*
X306406D03*
X302406D03*
X314500Y719800D03*
X355200Y328800D03*
X466000Y65500D03*
X457700D03*
X474400D03*
X500238Y130550D03*
X478800Y119300D03*
X477466Y182820D03*
X471681Y306512D03*
X476200Y359600D03*
X480700Y397600D03*
X499906Y771698D03*
X495906D03*
X491906Y820698D03*
X487906D03*
X495978Y820731D03*
X504248Y130550D03*
X528709Y291483D03*
X523906Y771698D03*
X507906D03*
X519906D03*
X503906D03*
X515906D03*
X511906D03*
X528100Y771600D03*
X558263Y133520D03*
X570100Y202300D03*
X541681Y291076D03*
X563531Y373380D03*
X558531Y380880D03*
X631363Y228408D03*
X623363D03*
X608090Y330660D03*
X632000Y333900D03*
X636000D03*
X617000Y375900D03*
X623000D03*
X640000Y333900D03*
X718302Y3324D03*
X736500Y24300D03*
X713375Y24502D03*
X724820Y15040D03*
X720700Y14970D03*
X728960Y15130D03*
X720840Y56440D03*
X742700Y11600D03*
X769400Y104200D03*
X838252Y14300D03*
X834252D03*
X830252D03*
X826252D03*
X822252D03*
X854400D03*
X846252D03*
X842252D03*
X873406Y748624D03*
X869406Y748698D03*
X865406D03*
X861406Y797698D03*
X857406D03*
X865478Y797731D03*
X891301Y13177D03*
X877406Y748698D03*
X893406D03*
X889406D03*
X885406D03*
X881406D03*
X897600Y748600D03*
X938000Y23300D03*
X911000Y89800D03*
X915500D03*
X920000D03*
X933500D03*
X929000D03*
X924500D03*
X938000D03*
X956000D03*
X1005176Y41562D03*
X1000683Y45750D03*
X1010676Y41562D03*
X1068809Y13342D03*
X1249679Y129895D03*
X1253719D03*
X1274500Y338800D03*
X1278500D03*
X1265500Y390300D03*
X1269500D03*
X1273500D03*
X1261500D03*
X1304000Y12800D03*
Y36300D03*
Y59800D03*
Y83300D03*
X1311000Y278800D03*
X1282500Y338800D03*
X1286500D03*
X1290500D03*
X1294500D03*
X1302500D03*
X1298500D03*
X1310128Y677167D03*
X1306128Y726167D03*
X1302128D03*
X1310200Y726200D03*
X1335100Y141970D03*
X1338128Y677167D03*
X1322128D03*
X1334128D03*
X1318128D03*
X1330128D03*
X1314128D03*
X1326128D03*
X1342300Y676800D03*
X1322400Y669600D03*
X1378134Y173509D03*
X1359124Y171420D03*
X1359011Y178984D03*
G54D22*
X31500Y441800D03*
Y434200D03*
X31000Y423800D03*
Y416200D03*
X37300Y712200D03*
Y704600D03*
X124051Y647136D03*
Y654736D03*
X153421Y301558D03*
Y309158D03*
X161400Y301600D03*
Y309200D03*
X276300Y621600D03*
Y629200D03*
Y644100D03*
Y651700D03*
X335000Y179700D03*
Y187300D03*
X343000Y179700D03*
Y187300D03*
X589500Y356300D03*
Y348700D03*
X574000Y356300D03*
Y348700D03*
X581700Y356300D03*
Y348700D03*
X660263Y228808D03*
Y236408D03*
X704700Y278200D03*
Y285800D03*
X732600Y238700D03*
X724600D03*
X716600D03*
X708600D03*
X732600Y246300D03*
X724600D03*
X716600D03*
X708600D03*
X712300Y278200D03*
X719900D03*
X727500D03*
X735100D03*
X712300Y285800D03*
X719900D03*
X727500D03*
X735100D03*
X748237Y205992D03*
Y198392D03*
X923900Y47800D03*
Y55400D03*
X971400Y39400D03*
Y31800D03*
Y48800D03*
Y56400D03*
X979400Y39400D03*
Y31800D03*
Y48800D03*
Y56400D03*
X1177000Y228600D03*
Y221000D03*
X1168000Y228600D03*
Y221000D03*
X1177000Y267200D03*
Y274800D03*
X1168000Y267200D03*
Y274800D03*
X1213000Y228600D03*
Y221000D03*
X1204000Y228600D03*
Y221000D03*
X1195000Y228600D03*
Y221000D03*
X1186000Y228600D03*
Y221000D03*
X1212500Y267200D03*
Y274800D03*
X1195000Y267200D03*
Y274800D03*
X1204000Y267200D03*
Y274800D03*
X1186000Y267200D03*
Y274800D03*
G54D124*
X889700Y23000D03*
X895300D03*
G54D133*
X1309410Y170203D03*
G54D115*
X626110Y366593D03*
Y346607D03*
X639890D03*
Y366593D03*
G54D40*
X53583Y283136D03*
Y312664D03*
X54100Y427970D03*
Y426000D03*
Y424030D03*
Y422065D03*
X41900D03*
Y424030D03*
Y426000D03*
Y427970D03*
X54100Y429935D03*
X41900D03*
X89417Y283136D03*
Y312664D03*
X253200Y633930D03*
Y635900D03*
Y637870D03*
Y639835D03*
X265400D03*
Y637870D03*
Y635900D03*
Y633930D03*
X253200Y631965D03*
X265400D03*
G54D106*
X530152Y175634D03*
X522278D03*
X530152Y192366D03*
X522278D03*
X569522Y175634D03*
X561648D03*
X553774D03*
X545900D03*
X538026D03*
X569522Y192366D03*
X561648D03*
X553774D03*
X545900D03*
X538026D03*
G54D32*
X25300Y742600D03*
X58300Y330900D03*
X62800Y330600D03*
X64500Y424200D03*
X32000Y476700D03*
X49000D03*
X53200Y470100D03*
X55261Y510841D03*
X51300Y713100D03*
X43300D03*
X57200Y694000D03*
X80300Y262600D03*
X95670Y344211D03*
X91600Y344100D03*
X70591Y366599D03*
X70654Y374260D03*
X80000Y406900D03*
X84274Y402541D03*
X96046Y426730D03*
X92500Y473200D03*
X96700Y473100D03*
X88000Y610300D03*
X72000Y609700D03*
X76000D03*
X66000Y601700D03*
X97500Y635200D03*
X65000Y766500D03*
X108500Y298100D03*
X128180Y314414D03*
X103998Y344250D03*
X99887Y344275D03*
X103617Y336215D03*
X100200Y388300D03*
X100076Y434130D03*
X111500Y461200D03*
X107500D03*
X106900Y735500D03*
X126000Y780700D03*
X151600Y409700D03*
X133000Y461200D03*
X137000D03*
X142000Y456700D03*
X160000Y778200D03*
X164500Y816200D03*
X196018Y199756D03*
X191018D03*
X197841Y433842D03*
X184116Y462010D03*
X192733Y461532D03*
X188150Y461905D03*
X172800Y461200D03*
X197500Y573732D03*
X191500Y601700D03*
X195500Y594200D03*
Y586700D03*
X199500Y699200D03*
X167200Y723100D03*
X199500Y754700D03*
X171700Y761100D03*
X224900Y112800D03*
X224600Y123500D03*
X207369Y151184D03*
X220969Y438372D03*
X209400Y453500D03*
X213500D03*
X225000Y521800D03*
X229000Y529200D03*
X201500Y573732D03*
X226200Y575862D03*
X204000Y737200D03*
Y792700D03*
X261200Y105300D03*
X235505Y148062D03*
X236331Y233780D03*
X258900Y297000D03*
X263000Y296800D03*
X266729Y349340D03*
X244900Y434300D03*
X262900Y433800D03*
X257500Y450938D03*
X253400Y450900D03*
X242500Y529200D03*
X253500D03*
X258000Y521200D03*
X245300Y639100D03*
X277500Y137200D03*
X272900Y296700D03*
X299639Y336101D03*
X294406Y723098D03*
X290406D03*
X286406D03*
X282406D03*
X298406D03*
X278406Y772098D03*
X274406D03*
X282478Y772131D03*
X316646Y296975D03*
X302700Y297962D03*
X320662Y296990D03*
X315300Y340700D03*
X310406Y723098D03*
X306406D03*
X302406D03*
X314500Y723200D03*
X355200Y332200D03*
X466000Y68900D03*
X457700D03*
X474400D03*
X500238Y133950D03*
X478800Y122700D03*
X477466Y186220D03*
X471681Y309912D03*
X476200Y363000D03*
X480700Y401000D03*
X499906Y775098D03*
X495906D03*
X491906Y824098D03*
X487906D03*
X495978Y824131D03*
X504248Y133950D03*
X528709Y294883D03*
X523906Y775098D03*
X507906D03*
X519906D03*
X503906D03*
X515906D03*
X511906D03*
X528100Y775000D03*
X558263Y136920D03*
X570100Y205700D03*
X541681Y294476D03*
X563531Y376780D03*
X558531Y384280D03*
X631363Y231808D03*
X623363D03*
X608090Y334060D03*
X632000Y337300D03*
X636000D03*
X617000Y379300D03*
X623000D03*
X640000Y337300D03*
X718302Y6724D03*
X736500Y27700D03*
X713375Y27902D03*
X724820Y18440D03*
X720700Y18370D03*
X728960Y18530D03*
X720840Y59840D03*
X742700Y15000D03*
X769400Y107600D03*
X838252Y17700D03*
X834252D03*
X830252D03*
X826252D03*
X822252D03*
X854400D03*
X846252D03*
X842252D03*
X873406Y752024D03*
X869406Y752098D03*
X865406D03*
X861406Y801098D03*
X857406D03*
X865478Y801131D03*
X891301Y16577D03*
X877406Y752098D03*
X893406D03*
X889406D03*
X885406D03*
X881406D03*
X897600Y752000D03*
X938000Y26700D03*
X911000Y93200D03*
X915500D03*
X920000D03*
X933500D03*
X929000D03*
X924500D03*
X938000D03*
X956000D03*
X1005176Y44962D03*
X1000683Y49150D03*
X1010676Y44962D03*
X1068809Y16742D03*
X1249679Y133295D03*
X1253719D03*
X1274500Y342200D03*
X1278500D03*
X1265500Y393700D03*
X1269500D03*
X1273500D03*
X1261500D03*
X1304000Y16200D03*
Y39700D03*
Y63200D03*
Y86700D03*
X1311000Y282200D03*
X1282500Y342200D03*
X1286500D03*
X1290500D03*
X1294500D03*
X1302500D03*
X1298500D03*
X1310128Y680567D03*
X1306128Y729567D03*
X1302128D03*
X1310200Y729600D03*
X1335100Y145370D03*
X1338128Y680567D03*
X1322128D03*
X1334128D03*
X1318128D03*
X1330128D03*
X1314128D03*
X1326128D03*
X1342300Y680200D03*
X1322400Y673000D03*
X1359124Y174820D03*
X1378134Y176909D03*
X1359011Y182384D03*
G54D107*
X532909Y331641D03*
Y321441D03*
G54D134*
X1311262Y175228D03*
X1290978D03*
X1311262Y181958D03*
X1290978D03*
G54D125*
X885300Y64650D03*
Y57150D03*
X892900Y64650D03*
G54D41*
X56736Y279983D03*
Y315817D03*
X86264Y279983D03*
Y315817D03*
G54D50*
X64050Y739821D03*
Y737853D03*
Y735884D03*
Y733916D03*
Y731947D03*
Y729979D03*
X44550D03*
Y731947D03*
Y733916D03*
Y735884D03*
Y737853D03*
Y739821D03*
G54D116*
X635953Y346807D03*
X633984D03*
X632016D03*
X630047D03*
Y366393D03*
X632016D03*
X633984D03*
X635953D03*
X628079Y346807D03*
Y366393D03*
X637921Y346807D03*
Y366393D03*
G54D14*
X27300Y223000D03*
X37700Y693300D03*
X76450Y704950D03*
X114364Y132099D03*
X108224Y164187D03*
X123680Y315514D03*
X132400Y727600D03*
X111400D03*
X181838Y132011D03*
X548531Y368380D03*
X580178Y238769D03*
X994597Y58669D03*
G54D23*
X25000Y429700D03*
X47800Y763600D03*
X64900Y771100D03*
X68100Y259500D03*
X65965Y367608D03*
X69800Y763100D03*
X111400Y732500D03*
X132400D03*
X171094Y238161D03*
X290200Y706500D03*
X520909Y323741D03*
X612830Y335850D03*
X1028500Y65200D03*
X1357000Y265700D03*
G54D24*
X25000Y435300D03*
X47800Y769200D03*
X64900Y776700D03*
X68100Y265100D03*
X65965Y373208D03*
X69800Y768700D03*
X111400Y738100D03*
X132400D03*
X171094Y243761D03*
X290200Y712100D03*
X520909Y329341D03*
X612830Y341450D03*
X1028500Y70800D03*
X1357000Y271300D03*
G54D135*
X1307100Y296700D03*
X1298300Y300700D03*
Y292700D03*
G54D108*
X559109Y312241D03*
X574609D03*
X1353250Y192000D03*
X1368750D03*
G54D42*
X58705Y280483D03*
X60673D03*
X62642D03*
Y315317D03*
X60673D03*
X58705D03*
X64610Y280483D03*
X66579D03*
X68547D03*
X70516D03*
X72484D03*
X74453D03*
X76421D03*
X78390D03*
X80358D03*
X82327D03*
X84295D03*
X78390Y315317D03*
X76421D03*
X74453D03*
X72484D03*
X70516D03*
X68547D03*
X66579D03*
X64610D03*
X84295D03*
X82327D03*
X80358D03*
G54D51*
X61190Y724850D03*
X47410D03*
Y744950D03*
X61190D03*
X562501Y351980D03*
X560531D03*
X558561D03*
X556596D03*
Y364180D03*
X558561D03*
X560531D03*
X562501D03*
X564466Y351980D03*
Y364180D03*
G54D117*
X623007Y349710D03*
Y363490D03*
X642993D03*
Y349710D03*
G54D15*
X27300Y217400D03*
X37700Y687700D03*
X76450Y699350D03*
X114364Y126499D03*
X108224Y158587D03*
X123680Y309914D03*
X132400Y722000D03*
X111400D03*
X181838Y126411D03*
X548531Y362780D03*
X580178Y233169D03*
X994597Y53069D03*
G54D126*
X892900Y57935D03*
X1049935Y28600D03*
G54D60*
X96860Y494107D03*
Y496307D03*
G54D33*
X4100Y865800D03*
X46678Y-681D03*
X50400Y826100D03*
X93450Y562220D03*
X107400Y119000D03*
X226500Y424700D03*
X854450Y99220D03*
X1037450Y272220D03*
X1374900Y761800D03*
X1383700Y138500D03*
X1396600Y862800D03*
G54D34*
X31600Y204900D03*
X46950Y200100D03*
X52700Y775300D03*
X82350Y199400D03*
X67800Y204800D03*
X85650Y702150D03*
X161400Y727900D03*
Y748900D03*
X154200Y783000D03*
Y804000D03*
X193700Y704000D03*
Y725000D03*
Y759500D03*
Y780500D03*
X208200Y530000D03*
X286200Y126000D03*
X282900Y630200D03*
X305039Y340501D03*
X306700Y712400D03*
X470400Y367800D03*
Y388800D03*
X523900Y829700D03*
X646100Y814500D03*
X727909Y68898D03*
X708224D03*
X747594D03*
X846134Y-1815D03*
X1169900Y814200D03*
X1296806Y7874D03*
Y31496D03*
Y55118D03*
Y78740D03*
X1299000Y818400D03*
X1341200Y246500D03*
G54D16*
X28400Y270875D03*
Y287925D03*
G54D25*
X25200Y424000D03*
X28500Y720400D03*
X31548Y310872D03*
X31612Y306674D03*
X45000Y321400D03*
X32700Y429000D03*
X40200Y466000D03*
X60800Y470100D03*
Y474200D03*
X40700Y484500D03*
X34000Y533500D03*
X58800Y713000D03*
X79691Y365075D03*
X79505Y360727D03*
X89100Y360000D03*
X84390Y392665D03*
X97049Y477241D03*
X82969Y513090D03*
X83844Y508831D03*
X95700Y506000D03*
X83844Y504831D03*
X66969Y502220D03*
X95700Y526500D03*
Y522500D03*
Y530500D03*
X82969Y517090D03*
X95700Y534500D03*
Y518500D03*
Y538500D03*
X84200Y534300D03*
Y538300D03*
X71120Y535931D03*
Y531831D03*
X83700Y606500D03*
X77200Y582000D03*
X83300Y681900D03*
X90900D03*
X79200Y723200D03*
X83000Y753700D03*
Y757900D03*
X110500Y212200D03*
X109500Y230100D03*
X101300Y272000D03*
X99007Y281582D03*
X104200Y294900D03*
Y290900D03*
X103890Y319780D03*
X103940Y315650D03*
X104100Y324100D03*
X104000Y328600D03*
X126400Y392300D03*
X102600Y732300D03*
X118200Y756000D03*
X135880Y311214D03*
X157500Y402200D03*
X146769Y636620D03*
X137251Y648436D03*
X140600Y727800D03*
X160200Y808500D03*
X182539Y450747D03*
X166027Y447721D03*
X167400Y753400D03*
X211149Y143587D03*
X206300Y251000D03*
X216900Y446000D03*
X223200Y469000D03*
Y465000D03*
X213200Y478000D03*
X221700Y486600D03*
X213200Y502000D03*
Y506000D03*
X227350Y491200D03*
X227362Y495300D03*
X213200Y534500D03*
Y542500D03*
Y538500D03*
Y550500D03*
Y570500D03*
X226072Y563994D03*
X199700Y729500D03*
Y785000D03*
X251800Y339700D03*
X264929Y334140D03*
X260900Y443300D03*
X281200Y126000D03*
X288740Y149350D03*
X281200Y145500D03*
X297688Y578165D03*
Y583165D03*
Y588665D03*
X312482Y293550D03*
X319100Y538300D03*
X347400Y335600D03*
X336500Y318900D03*
X486660Y13180D03*
X486670Y26720D03*
X486700Y49880D03*
Y73380D03*
X473360Y143008D03*
X494300Y166000D03*
X476400Y393300D03*
X507642Y130547D03*
X508500Y186500D03*
X554180Y133550D03*
X538412Y159035D03*
X538325Y163463D03*
X549399Y291069D03*
X561731Y342980D03*
X584763Y228608D03*
X593163Y211308D03*
X623263Y209608D03*
X630863Y209408D03*
Y217608D03*
X625563Y238108D03*
X630863Y213508D03*
X608400Y348200D03*
X655700Y340100D03*
X663200D03*
X655700Y344600D03*
Y372100D03*
Y376600D03*
X663200D03*
X655700Y367100D03*
Y362100D03*
Y352600D03*
Y348600D03*
X736500Y14000D03*
X738800Y114020D03*
X738780Y109410D03*
X759800Y35100D03*
Y26200D03*
X767600D03*
X757200Y64000D03*
X770900Y74000D03*
X761300Y98800D03*
Y94700D03*
X768900Y129400D03*
Y125300D03*
X801010Y26343D03*
X787600Y74100D03*
X777000Y135200D03*
X810200Y82400D03*
X810300Y94600D03*
Y98700D03*
X831260Y105630D03*
X815125Y123631D03*
Y127631D03*
X863900Y3900D03*
X865200Y28000D03*
Y36000D03*
X865700Y8000D03*
X865533Y44034D03*
X874700Y52800D03*
X903700Y341600D03*
Y363000D03*
Y354000D03*
X908200Y33000D03*
Y29000D03*
Y41000D03*
X930670Y23540D03*
X988117Y18587D03*
X1037021Y26921D03*
X1015178Y49109D03*
X1052186Y11208D03*
X1058060Y69355D03*
X1065883Y48832D03*
X1090700Y500D03*
Y5000D03*
X1090320Y27440D03*
X1090704Y36383D03*
X1090320Y22940D03*
X1090704Y40883D03*
X1079176Y18266D03*
X1089925Y14177D03*
X1090127Y18525D03*
X1077700Y68500D03*
X1249668Y141179D03*
X1248184Y145217D03*
X1292700Y295000D03*
X1313510Y145310D03*
X1314226Y151199D03*
X1328700Y290500D03*
X1320700Y294000D03*
X1366618Y168102D03*
G54D61*
X95252Y576388D03*
Y585612D03*
X101748Y576388D03*
Y585612D03*
G54D52*
X59221Y725150D03*
X57253D03*
X55284D03*
X53316D03*
X51347D03*
X49379D03*
Y744650D03*
X51347D03*
X53316D03*
X55284D03*
X57253D03*
X59221D03*
G54D70*
X128850Y287500D03*
X125100D03*
X121350D03*
Y298100D03*
X125100D03*
X128850D03*
X153130Y170531D03*
X149380D03*
X145630D03*
Y181131D03*
X149380D03*
X153130D03*
G54D118*
X623207Y361521D03*
Y351679D03*
Y359553D03*
Y357584D03*
Y355616D03*
Y353647D03*
X642793Y361521D03*
Y359553D03*
Y357584D03*
Y355616D03*
Y353647D03*
Y351679D03*
G54D136*
X1337000Y263250D03*
G54D43*
X31600Y321200D03*
X46900Y394400D03*
X90830Y273800D03*
X68300Y417000D03*
X91285Y489504D03*
Y486004D03*
X79300Y719300D03*
X104400Y306700D03*
X112351Y638436D03*
X127700Y714300D03*
Y710800D03*
X146869Y640420D03*
X146851Y648436D03*
X137351Y643936D03*
X146851D03*
X181421Y598436D03*
X281300Y122000D03*
X278100Y634900D03*
X328892Y295900D03*
X319300Y534500D03*
X623363Y213608D03*
X891200Y51500D03*
X908300Y45000D03*
Y48500D03*
X945581Y25374D03*
X1022663Y17398D03*
X1080300Y57000D03*
Y60500D03*
Y53500D03*
Y50000D03*
X1129700Y129800D03*
Y133300D03*
X1320800Y286500D03*
G54D109*
X560531Y358080D03*
G54D127*
G01X127746Y-260199D02*
X95746D01*
G01X127746Y-276199D02*
Y-356199D01*
G01D02*
X1310146D01*
G01X127746Y-311699D02*
X1310146D01*
G01X123746Y-260199D02*
G02I-12000J0D01*
G01X118596D02*
G02I-6850J0D01*
G01X111746Y-276199D02*
Y-244199D01*
G01X127746Y-276199D02*
X1310146D01*
G01X522646D02*
Y-356199D01*
G01X660146Y-276199D02*
Y-356199D01*
G01X775146Y-276199D02*
Y-356199D01*
G01X942646Y-276199D02*
Y-356199D01*
G01X1112646Y-276199D02*
Y-356199D01*
G01X1310146Y-276199D02*
Y-356199D01*
G01X1342146Y-260199D02*
X1310146D01*
G01X1338146D02*
G02I-12000J0D01*
G01X1332996D02*
G02I-6850J0D01*
G01X1326146Y-276199D02*
Y-244199D01*
X876378Y122047D03*
Y125984D03*
X880315Y118110D03*
Y122047D03*
Y125984D03*
X884252Y122047D03*
Y125984D03*
X876378Y251968D03*
Y255905D03*
X880315Y251968D03*
Y255905D03*
Y259842D03*
X884252Y251968D03*
Y255905D03*
X1010236Y122047D03*
Y125984D03*
X1014173Y118110D03*
Y122047D03*
Y125984D03*
X1018110Y122047D03*
Y125984D03*
X1010236Y251968D03*
Y255905D03*
X1014173Y251968D03*
Y255905D03*
Y259842D03*
X1018110Y251968D03*
Y255905D03*
G54D137*
G01X145579Y-328699D02*
Y-346199D01*
X154313D01*
G01X167446Y-334533D02*
Y-346199D01*
G01Y-329866D02*
X167009Y-329574D01*
Y-328991D01*
X167446Y-328699D01*
X167883Y-328991D01*
Y-329574D01*
X167446Y-329866D01*
G01X181889Y-350574D02*
X183418Y-351741D01*
X185164Y-352032D01*
X186692Y-351741D01*
X188003Y-350283D01*
X188876Y-348241D01*
Y-334533D01*
G01Y-336866D02*
X188003Y-335699D01*
X186692Y-334824D01*
X185164Y-334533D01*
X183418Y-335116D01*
X182326Y-336282D01*
X181452Y-338324D01*
X181016Y-340366D01*
X181234Y-342116D01*
X182108Y-344158D01*
X183418Y-345616D01*
X185164Y-346199D01*
X186474Y-345907D01*
X188003Y-344741D01*
X188876Y-343575D01*
G01X198734Y-346199D02*
Y-328699D01*
G01Y-337157D02*
X199826Y-335699D01*
X200918Y-334824D01*
X202664Y-334533D01*
X203974Y-334824D01*
X205503Y-335991D01*
X206158Y-337741D01*
Y-346199D01*
G01X219946Y-328699D02*
Y-346199D01*
G01X216889Y-334533D02*
X223003D01*
G01X233734Y-346199D02*
Y-334533D01*
G01Y-337449D02*
X234608Y-335991D01*
X235918Y-334824D01*
X237664Y-334533D01*
X239192Y-334824D01*
X240503Y-335991D01*
X241158Y-338032D01*
Y-346199D01*
G01X254946Y-334533D02*
Y-346199D01*
G01Y-329866D02*
X254509Y-329574D01*
Y-328991D01*
X254946Y-328699D01*
X255383Y-328991D01*
Y-329574D01*
X254946Y-329866D01*
G01X268734Y-346199D02*
Y-334533D01*
G01Y-337449D02*
X269608Y-335991D01*
X270918Y-334824D01*
X272664Y-334533D01*
X274192Y-334824D01*
X275503Y-335991D01*
X276158Y-338032D01*
Y-346199D01*
G01X286889Y-350574D02*
X288418Y-351741D01*
X290164Y-352032D01*
X291692Y-351741D01*
X293003Y-350283D01*
X293876Y-348241D01*
Y-334533D01*
G01Y-336866D02*
X293003Y-335699D01*
X291692Y-334824D01*
X290164Y-334533D01*
X288418Y-335116D01*
X287326Y-336282D01*
X286452Y-338324D01*
X286016Y-340366D01*
X286234Y-342116D01*
X287108Y-344158D01*
X288418Y-345616D01*
X290164Y-346199D01*
X291474Y-345907D01*
X293003Y-344741D01*
X293876Y-343575D01*
G01X320579Y-346199D02*
Y-328699D01*
X325819D01*
X327566Y-329574D01*
X328876Y-331616D01*
X329313Y-333949D01*
X328876Y-336282D01*
X327784Y-338032D01*
X325819Y-338908D01*
X320579D01*
G01X346813Y-346199D02*
X338079D01*
Y-328699D01*
X346813D01*
G01X343319Y-337157D02*
X338079D01*
G01X361692Y-336866D02*
X362566Y-335991D01*
X363221Y-334533D01*
X363658Y-332490D01*
X363221Y-330741D01*
X362348Y-329574D01*
X360819Y-328699D01*
X354924D01*
Y-346199D01*
X362129D01*
X363658Y-345033D01*
X364531Y-343282D01*
X364968Y-341241D01*
X364531Y-339199D01*
X363221Y-337449D01*
X361692Y-336866D01*
X354924D01*
G01X390579Y-346199D02*
Y-328699D01*
X395819D01*
X397566Y-329574D01*
X398876Y-331616D01*
X399313Y-333949D01*
X398876Y-336282D01*
X397784Y-338032D01*
X395819Y-338908D01*
X390579D01*
G01X406769Y-346199D02*
Y-328699D01*
X412446Y-343282D01*
X418123Y-328699D01*
Y-346199D01*
G01X434749Y-330158D02*
X433439Y-329282D01*
X431911Y-328699D01*
X430164D01*
X428199Y-329574D01*
X426671Y-331032D01*
X425579Y-332783D01*
X424706Y-335699D01*
X424487Y-338324D01*
X424924Y-340949D01*
X425579Y-342699D01*
X426889Y-344449D01*
X428418Y-345616D01*
X429946Y-346199D01*
X431474D01*
X433003Y-345616D01*
X434313Y-344741D01*
X435405Y-343575D01*
G01X460579Y-346199D02*
Y-328699D01*
X465819D01*
X467566Y-329574D01*
X468876Y-331616D01*
X469313Y-333949D01*
X468876Y-336282D01*
X467784Y-338032D01*
X465819Y-338908D01*
X460579D01*
G01X476987Y-328699D02*
X482446Y-346199D01*
X487905Y-328699D01*
G01X499946D02*
Y-346199D01*
G01X494924Y-328699D02*
X504968D01*
G01X284269Y-301199D02*
Y-283699D01*
X289946Y-298282D01*
X295623Y-283699D01*
Y-301199D01*
G01X307446D02*
X306136Y-300907D01*
X304826Y-299741D01*
X303952Y-297699D01*
X303516Y-295366D01*
X303952Y-293032D01*
X304826Y-290991D01*
X306136Y-289824D01*
X307446Y-289533D01*
X308756Y-289824D01*
X310066Y-290991D01*
X310939Y-293032D01*
X311158Y-295366D01*
X310939Y-297699D01*
X310066Y-299741D01*
X308756Y-300907D01*
X307446Y-301199D01*
G01X328876Y-283699D02*
Y-301199D01*
G01Y-298575D02*
X328003Y-300033D01*
X326692Y-300907D01*
X325164Y-301199D01*
X323418Y-300616D01*
X322108Y-299158D01*
X321234Y-297408D01*
X321016Y-295366D01*
X321234Y-293324D01*
X322108Y-291574D01*
X323418Y-290116D01*
X325164Y-289533D01*
X326692Y-289824D01*
X327784Y-290408D01*
X328876Y-291574D01*
G01X339171Y-293324D02*
X346158D01*
X345503Y-291282D01*
X344411Y-290116D01*
X342883Y-289533D01*
X341354Y-289824D01*
X340044Y-290699D01*
X339171Y-292741D01*
X338734Y-294491D01*
Y-296241D01*
X339171Y-297991D01*
X340263Y-299741D01*
X341573Y-300907D01*
X343101Y-301199D01*
X344629Y-300616D01*
X346158Y-298866D01*
G01X359946Y-301199D02*
Y-283699D01*
G01X556346Y-346199D02*
Y-328699D01*
X553726Y-332199D01*
G01Y-346199D02*
X558966D01*
G01X569043Y-343575D02*
X570352Y-345033D01*
X571881Y-345907D01*
X573846Y-346199D01*
X575811Y-345616D01*
X577339Y-344449D01*
X578431Y-342408D01*
X578649Y-340074D01*
X578213Y-337741D01*
X577121Y-336282D01*
X575592Y-335116D01*
X574064Y-334824D01*
X572536Y-335116D01*
X570571Y-336282D01*
X571226Y-328699D01*
X577121D01*
G01X591346Y-346199D02*
Y-328699D01*
X588726Y-332199D01*
G01Y-346199D02*
X593966D01*
G01X608846Y-328699D02*
X607099Y-329282D01*
X605789Y-330741D01*
X604916Y-332490D01*
X604261Y-334824D01*
X604043Y-337449D01*
X604261Y-340074D01*
X604916Y-342408D01*
X605789Y-344158D01*
X607099Y-345616D01*
X608846Y-346199D01*
X610592Y-345616D01*
X611903Y-344158D01*
X612776Y-342408D01*
X613431Y-340074D01*
X613649Y-337449D01*
X613431Y-334824D01*
X612776Y-332490D01*
X611903Y-330741D01*
X610592Y-329282D01*
X608846Y-328699D01*
G01X621543Y-343575D02*
X622852Y-345033D01*
X624381Y-345907D01*
X626346Y-346199D01*
X628311Y-345616D01*
X629839Y-344449D01*
X630931Y-342408D01*
X631149Y-340074D01*
X630713Y-337741D01*
X629621Y-336282D01*
X628092Y-335116D01*
X626564Y-334824D01*
X625036Y-335116D01*
X623071Y-336282D01*
X623726Y-328699D01*
X629621D01*
G01X543229Y-301199D02*
Y-283699D01*
X548469D01*
X550216Y-284574D01*
X551526Y-286616D01*
X551963Y-288949D01*
X551526Y-291282D01*
X550434Y-293032D01*
X548469Y-293908D01*
X543229D01*
G01X569899Y-285158D02*
X568589Y-284282D01*
X567061Y-283699D01*
X565314D01*
X563349Y-284574D01*
X561821Y-286032D01*
X560729Y-287783D01*
X559856Y-290699D01*
X559637Y-293324D01*
X560074Y-295949D01*
X560729Y-297699D01*
X562039Y-299449D01*
X563568Y-300616D01*
X565096Y-301199D01*
X566624D01*
X568153Y-300616D01*
X569463Y-299741D01*
X570555Y-298575D01*
G01X584342Y-291866D02*
X585216Y-290991D01*
X585871Y-289533D01*
X586308Y-287490D01*
X585871Y-285741D01*
X584998Y-284574D01*
X583469Y-283699D01*
X577574D01*
Y-301199D01*
X584779D01*
X586308Y-300033D01*
X587181Y-298282D01*
X587618Y-296241D01*
X587181Y-294199D01*
X585871Y-292449D01*
X584342Y-291866D01*
X577574D01*
G01X593546Y-307032D02*
X606646D01*
G01X612574Y-301199D02*
Y-283699D01*
X622618Y-301199D01*
Y-283699D01*
G01X635096Y-301199D02*
X633349Y-300907D01*
X631821Y-299741D01*
X630511Y-297991D01*
X629637Y-295949D01*
X629201Y-293616D01*
Y-291282D01*
X629637Y-288949D01*
X630511Y-286907D01*
X631821Y-285158D01*
X633349Y-283991D01*
X635096Y-283699D01*
X636842Y-283991D01*
X638371Y-285158D01*
X639681Y-286907D01*
X640555Y-288949D01*
X640991Y-291282D01*
Y-293616D01*
X640555Y-295949D01*
X639681Y-297991D01*
X638371Y-299741D01*
X636842Y-300907D01*
X635096Y-301199D01*
G01X685937Y-283699D02*
X691396Y-301199D01*
X696855Y-283699D01*
G01X713263Y-301199D02*
X704529D01*
Y-283699D01*
X713263D01*
G01X709769Y-292157D02*
X704529D01*
G01X722029Y-301199D02*
Y-283699D01*
X727488D01*
X729234Y-284574D01*
X730326Y-285741D01*
X730763Y-288074D01*
X730326Y-290408D01*
X729016Y-291866D01*
X727488Y-292741D01*
X722029D01*
G01X727488D02*
X730763Y-301199D01*
G01X743896Y-301782D02*
X743459Y-301491D01*
Y-300907D01*
X743896Y-300616D01*
X744333Y-300907D01*
Y-301491D01*
X743896Y-301782D01*
G01X717646Y-346199D02*
Y-328699D01*
X715026Y-332199D01*
G01Y-346199D02*
X720266D01*
G01X832596Y-328699D02*
Y-346199D01*
G01X827574Y-328699D02*
X837618D01*
G01X845511Y-343866D02*
X847258Y-345324D01*
X849223Y-346199D01*
X850969D01*
X852716Y-345324D01*
X854026Y-343866D01*
X854681Y-341824D01*
X854244Y-339783D01*
X853153Y-338032D01*
X851188Y-336866D01*
X848568Y-336282D01*
X847039Y-335116D01*
X846384Y-333074D01*
X846821Y-331032D01*
X847913Y-329574D01*
X849441Y-328699D01*
X850969D01*
X852498Y-329282D01*
X853808Y-330741D01*
G01X861919Y-346199D02*
Y-328699D01*
X867596Y-343282D01*
X873273Y-328699D01*
Y-346199D01*
G01X880293D02*
Y-328699D01*
X884659D01*
X886406Y-329574D01*
X887716Y-330741D01*
X888808Y-332490D01*
X889681Y-334533D01*
X889899Y-337449D01*
X889681Y-340366D01*
X888808Y-342408D01*
X887716Y-344158D01*
X886406Y-345324D01*
X884659Y-346199D01*
X880293D01*
G01X819479Y-283699D02*
Y-301199D01*
X828213D01*
G01X845276D02*
Y-289533D01*
G01Y-291574D02*
X844403Y-290408D01*
X843092Y-289824D01*
X841564Y-289533D01*
X840036Y-290116D01*
X838726Y-291282D01*
X837852Y-293032D01*
X837416Y-295366D01*
X837852Y-297699D01*
X838726Y-299449D01*
X840036Y-300616D01*
X841564Y-301199D01*
X843092Y-300907D01*
X844403Y-300033D01*
X845276Y-298866D01*
G01X854261Y-306449D02*
X855571Y-307032D01*
X857318Y-306449D01*
X858409Y-305283D01*
X859283Y-303824D01*
X860592Y-299158D01*
X863431Y-289533D01*
G01X856444D02*
X860592Y-299158D01*
G01X873071Y-293324D02*
X880058D01*
X879403Y-291282D01*
X878311Y-290116D01*
X876783Y-289533D01*
X875254Y-289824D01*
X873944Y-290699D01*
X873071Y-292741D01*
X872634Y-294491D01*
Y-296241D01*
X873071Y-297991D01*
X874163Y-299741D01*
X875473Y-300907D01*
X877001Y-301199D01*
X878529Y-300616D01*
X880058Y-298866D01*
G01X890789Y-301199D02*
Y-289533D01*
G01Y-291866D02*
X891881Y-290699D01*
X892973Y-289824D01*
X894501Y-289533D01*
X895592Y-289824D01*
X896903Y-290699D01*
G01X959846Y-328699D02*
X962902Y-346199D01*
X966396Y-328699D01*
X969889Y-346199D01*
X972946Y-328699D01*
G01X979529Y-346199D02*
Y-328699D01*
X984769D01*
X986516Y-329574D01*
X987826Y-331616D01*
X988263Y-333949D01*
X987826Y-336282D01*
X986734Y-338032D01*
X984769Y-338908D01*
X979529D01*
G01X996811Y-346199D02*
Y-328699D01*
G01X1005981D02*
Y-346199D01*
G01Y-337449D02*
X996811D01*
G01X1016058Y-340366D02*
X1021734D01*
G01X1031593Y-346199D02*
Y-328699D01*
G01X1039889D02*
X1031593Y-339491D01*
G01X1041199Y-346199D02*
X1035304Y-334533D01*
G01X1058263Y-346199D02*
X1049529D01*
Y-328699D01*
X1058263D01*
G01X1054769Y-337157D02*
X1049529D01*
G01X1066374Y-346199D02*
Y-328699D01*
X1076418Y-346199D01*
Y-328699D01*
G01X1083874Y-346199D02*
Y-328699D01*
X1093918Y-346199D01*
Y-328699D01*
G01X961593Y-301199D02*
Y-283699D01*
X965959D01*
X967706Y-284574D01*
X969016Y-285741D01*
X970108Y-287490D01*
X970981Y-289533D01*
X971199Y-292449D01*
X970981Y-295366D01*
X970108Y-297408D01*
X969016Y-299158D01*
X967706Y-300324D01*
X965959Y-301199D01*
X961593D01*
G01X980621Y-293324D02*
X987608D01*
X986953Y-291282D01*
X985861Y-290116D01*
X984333Y-289533D01*
X982804Y-289824D01*
X981494Y-290699D01*
X980621Y-292741D01*
X980184Y-294491D01*
Y-296241D01*
X980621Y-297991D01*
X981713Y-299741D01*
X983023Y-300907D01*
X984551Y-301199D01*
X986079Y-300616D01*
X987608Y-298866D01*
G01X998121Y-299158D02*
X999213Y-300324D01*
X1000741Y-301199D01*
X1002051D01*
X1003361Y-300616D01*
X1004234Y-299741D01*
X1004671Y-298575D01*
X1004453Y-296824D01*
X1003579Y-295949D01*
X999649Y-294199D01*
X998776Y-292157D01*
X999213Y-290699D01*
X1000086Y-289824D01*
X1001396Y-289533D01*
X1002706Y-289824D01*
X1004016Y-290699D01*
G01X1018896Y-289533D02*
Y-301199D01*
G01Y-284866D02*
X1018459Y-284574D01*
Y-283991D01*
X1018896Y-283699D01*
X1019333Y-283991D01*
Y-284574D01*
X1018896Y-284866D01*
G01X1033339Y-305574D02*
X1034868Y-306741D01*
X1036614Y-307032D01*
X1038142Y-306741D01*
X1039453Y-305283D01*
X1040326Y-303241D01*
Y-289533D01*
G01Y-291866D02*
X1039453Y-290699D01*
X1038142Y-289824D01*
X1036614Y-289533D01*
X1034868Y-290116D01*
X1033776Y-291282D01*
X1032902Y-293324D01*
X1032466Y-295366D01*
X1032684Y-297116D01*
X1033558Y-299158D01*
X1034868Y-300616D01*
X1036614Y-301199D01*
X1037924Y-300907D01*
X1039453Y-299741D01*
X1040326Y-298575D01*
G01X1050184Y-301199D02*
Y-289533D01*
G01Y-292449D02*
X1051058Y-290991D01*
X1052368Y-289824D01*
X1054114Y-289533D01*
X1055642Y-289824D01*
X1056953Y-290991D01*
X1057608Y-293032D01*
Y-301199D01*
G01X1068121Y-293324D02*
X1075108D01*
X1074453Y-291282D01*
X1073361Y-290116D01*
X1071833Y-289533D01*
X1070304Y-289824D01*
X1068994Y-290699D01*
X1068121Y-292741D01*
X1067684Y-294491D01*
Y-296241D01*
X1068121Y-297991D01*
X1069213Y-299741D01*
X1070523Y-300907D01*
X1072051Y-301199D01*
X1073579Y-300616D01*
X1075108Y-298866D01*
G01X1085839Y-301199D02*
Y-289533D01*
G01Y-291866D02*
X1086931Y-290699D01*
X1088023Y-289824D01*
X1089551Y-289533D01*
X1090642Y-289824D01*
X1091953Y-290699D01*
G01X1132596Y-346199D02*
Y-328699D01*
X1129976Y-332199D01*
G01Y-346199D02*
X1135216D01*
G01X1150096D02*
Y-328699D01*
X1147476Y-332199D01*
G01Y-346199D02*
X1152716D01*
G01X1163666Y-346782D02*
X1171526Y-328699D01*
G01X1185096Y-346199D02*
Y-328699D01*
X1182476Y-332199D01*
G01Y-346199D02*
X1187716D01*
G01X1198448Y-338908D02*
X1199976Y-336866D01*
X1201286Y-335699D01*
X1203033Y-335116D01*
X1204561Y-335699D01*
X1205653Y-336866D01*
X1206526Y-338616D01*
X1206744Y-340657D01*
X1206526Y-342408D01*
X1205653Y-344158D01*
X1204342Y-345616D01*
X1202814Y-346199D01*
X1201068Y-345616D01*
X1199539Y-343866D01*
X1198666Y-341241D01*
X1198448Y-338324D01*
X1198884Y-334533D01*
X1199539Y-332490D01*
X1200631Y-330449D01*
X1202159Y-328991D01*
X1203688Y-328699D01*
X1205216Y-329282D01*
X1206308Y-330741D01*
G01X1216166Y-346782D02*
X1224026Y-328699D01*
G01X1233448Y-331616D02*
X1234758Y-329866D01*
X1236286Y-328991D01*
X1238033Y-328699D01*
X1240216Y-329282D01*
X1241744Y-330741D01*
X1242181Y-332490D01*
X1241963Y-334241D01*
X1241089Y-335699D01*
X1236723Y-338616D01*
X1234758Y-340657D01*
X1233448Y-343575D01*
X1233011Y-346199D01*
X1242181D01*
G01X1255096Y-328699D02*
X1253349Y-329282D01*
X1252039Y-330741D01*
X1251166Y-332490D01*
X1250511Y-334824D01*
X1250293Y-337449D01*
X1250511Y-340074D01*
X1251166Y-342408D01*
X1252039Y-344158D01*
X1253349Y-345616D01*
X1255096Y-346199D01*
X1256842Y-345616D01*
X1258153Y-344158D01*
X1259026Y-342408D01*
X1259681Y-340074D01*
X1259899Y-337449D01*
X1259681Y-334824D01*
X1259026Y-332490D01*
X1258153Y-330741D01*
X1256842Y-329282D01*
X1255096Y-328699D01*
G01X1272596Y-346199D02*
Y-328699D01*
X1269976Y-332199D01*
G01Y-346199D02*
X1275216D01*
G01X1285948Y-338908D02*
X1287476Y-336866D01*
X1288786Y-335699D01*
X1290533Y-335116D01*
X1292061Y-335699D01*
X1293153Y-336866D01*
X1294026Y-338616D01*
X1294244Y-340657D01*
X1294026Y-342408D01*
X1293153Y-344158D01*
X1291842Y-345616D01*
X1290314Y-346199D01*
X1288568Y-345616D01*
X1287039Y-343866D01*
X1286166Y-341241D01*
X1285948Y-338324D01*
X1286384Y-334533D01*
X1287039Y-332490D01*
X1288131Y-330449D01*
X1289659Y-328991D01*
X1291188Y-328699D01*
X1292716Y-329282D01*
X1293808Y-330741D01*
G01X1180293Y-301199D02*
Y-283699D01*
X1184659D01*
X1186406Y-284574D01*
X1187716Y-285741D01*
X1188808Y-287490D01*
X1189681Y-289533D01*
X1189899Y-292449D01*
X1189681Y-295366D01*
X1188808Y-297408D01*
X1187716Y-299158D01*
X1186406Y-300324D01*
X1184659Y-301199D01*
X1180293D01*
G01X1206526D02*
Y-289533D01*
G01Y-291574D02*
X1205653Y-290408D01*
X1204342Y-289824D01*
X1202814Y-289533D01*
X1201286Y-290116D01*
X1199976Y-291282D01*
X1199102Y-293032D01*
X1198666Y-295366D01*
X1199102Y-297699D01*
X1199976Y-299449D01*
X1201286Y-300616D01*
X1202814Y-301199D01*
X1204342Y-300907D01*
X1205653Y-300033D01*
X1206526Y-298866D01*
G01X1220096Y-283699D02*
Y-301199D01*
G01X1217039Y-289533D02*
X1223153D01*
G01X1234321Y-293324D02*
X1241308D01*
X1240653Y-291282D01*
X1239561Y-290116D01*
X1238033Y-289533D01*
X1236504Y-289824D01*
X1235194Y-290699D01*
X1234321Y-292741D01*
X1233884Y-294491D01*
Y-296241D01*
X1234321Y-297991D01*
X1235413Y-299741D01*
X1236723Y-300907D01*
X1238251Y-301199D01*
X1239779Y-300616D01*
X1241308Y-298866D01*
G01X1425733Y-51181D02*
X-29385D01*
G01X-33322Y-47244D02*
G03X-29385Y-51181I3937J0D01*
G01X-33322Y-47244D02*
Y893701D01*
G01X-7874Y102402D02*
Y212205D01*
G01Y102402D02*
G03X0Y94528I7874J0D01*
G01Y212205D02*
G03X-7874I-3937J0D01*
G01Y237402D02*
G03X0I3937J-1D01*
G01X-7874D02*
Y406693D01*
G01X0D02*
G03X-7874I-3937J0D01*
G01Y431890D02*
G03X0I3937J0D01*
G01X-7874D02*
Y601181D01*
G01X0D02*
G03X-7874I-3937J0D01*
G01Y626378D02*
Y795669D01*
G01Y626378D02*
G03X0I3937J0D01*
G01Y795669D02*
G03X-7874I-3937J0D01*
G01Y820866D02*
G03X0I3937J0D01*
G01X-7874Y844488D02*
Y820866D01*
G01X-3937Y848425D02*
G03X-7874Y844488I0J-3937D01*
G01X93307Y848425D02*
X-3937D01*
G01X-29385Y897638D02*
G03X-33322Y893701I0J-3937D01*
G01X-29385Y897638D02*
X93307D01*
G01X98425Y94528D02*
X0D01*
G01X1400000Y36220D02*
G03X1398031Y38189I-1969J0D01*
G01X1396654D01*
G02X1394685Y40157I0J1969D01*
G01Y71654D01*
G02X1396654Y73622I1969J-1D01*
G01X1398031D01*
G03X1400000Y75591I0J1969D01*
G01Y836614D01*
G03X1396063Y840551I-3937J0D01*
G01X1368504D01*
G02X1363386Y845669I0J5118D01*
G01Y871654D01*
G03X1361417Y873622I-1969J-1D01*
G01X1358268D01*
G02X1356299Y875591I0J1969D01*
G01Y892521D01*
X1352363Y897638D01*
X1218110D01*
X1214173Y892520D01*
Y875984D01*
G02X1205512I-4331J0D01*
G01Y892520D01*
X1201575Y897638D01*
X1029528D01*
X1025591Y892520D01*
Y875591D01*
G02X1023622Y873622I-1969J0D01*
G01X1020472D01*
G03X1018504Y871654I0J-1968D01*
G01Y845669D01*
G02X1013386Y840551I-5118J0D01*
G01X1008433D01*
G03X988748Y820866I0J-19685D01*
G01Y650669D01*
G02X983748Y645669I-5000J0D01*
G01X926819D01*
G02X921819Y650669I0J5000D01*
G01Y820866D01*
G03X902134Y840551I-19685J0D01*
G01X872441D01*
G02X867323Y845669I0J5118D01*
G01Y871654D01*
G03X865354Y873622I-1969J-1D01*
G01X862205D01*
G02X860236Y875591I0J1969D01*
G01Y892521D01*
X856300Y897638D01*
X722048D01*
X718110Y892519D01*
Y875984D01*
G02X709449I-4331J0D01*
G01Y892520D01*
X705512Y897638D01*
X533465D01*
X529528Y892520D01*
Y875591D01*
G02X527559Y873622I-1969J0D01*
G01X524409D01*
G03X522441Y871654I0J-1968D01*
G01Y845669D01*
G02X517323Y840551I-5118J0D01*
G01X455118D01*
G02X450000Y845669I0J5118D01*
G01Y871654D01*
G03X448031Y873622I-1968J0D01*
G01X444882D01*
G02X442913Y875591I0J1969D01*
G01Y892521D01*
X438977Y897638D01*
X304725D01*
X300787Y892519D01*
Y875984D01*
G02X292126I-4331J0D01*
G01Y892521D01*
X288190Y897638D01*
X116142D01*
X112205Y892520D01*
Y875591D01*
G02X110236Y873622I-1969J0D01*
G01X107087D01*
G03X105118Y871654I0J-1969D01*
G01Y845669D01*
G02X100000Y840551I-5118J0D01*
G01X3937D01*
G03X0Y836614I0J-3937D01*
G01Y110276D01*
G03X7874Y102402I7874J0D01*
G01X196654D01*
G02X204528Y94528I0J-7874D01*
G01Y7874D01*
G03X212402Y0I7874J0D01*
G01X471014D01*
G02X478888Y-7874I0J-7874D01*
G01Y-11811D01*
G03X486762Y-19685I7874J0D01*
G01X1302165D01*
G03X1306102Y-15748I0J3937D01*
G01Y-3937D01*
G02X1310039Y0I3937J0D01*
G01X1396063D01*
G03X1400000Y3937I0J3937D01*
G01Y36220D01*
G01X93307Y848425D02*
G03X97244Y852362I0J3937D01*
G01Y893701D02*
Y852362D01*
G01Y893701D02*
G03X93307Y897638I-3937J0D01*
G01X192717Y94528D02*
X123622D01*
G01Y102402D02*
G03Y94528I0J-3937D01*
G01X98425D02*
G03Y102402I0J3937D01*
G01X196654Y0D02*
G03X204528Y-7874I7874J0D01*
G01X196654Y0D02*
Y29961D01*
G01X204528D02*
G03X196654I-3937J0D01*
G01Y55157D02*
Y90591D01*
G01Y55157D02*
G03X204528I3937J0D01*
G01X196654Y90591D02*
G03X192717Y94528I-3937J0D01*
G01X232077Y-7874D02*
G03Y0I0J3937D01*
G01Y-7874D02*
X204528D01*
G01X434439D02*
X257274D01*
G01Y0D02*
G03Y-7874I0J-3937D01*
G01X365945Y38188D02*
G03X367914Y40156I0J1969D01*
G01X354134D02*
G03X356103Y38188I1969J1D01*
G01D02*
X365945D01*
G01X354134Y71653D02*
Y40156D01*
G01X367914Y71653D02*
G03X365945Y73621I-1969J-1D01*
G01X356103D02*
G03X354134Y71653I0J-1969D01*
G01X365945Y73621D02*
X356103D01*
G01X367914Y40156D02*
Y71653D01*
G01X434439Y-7874D02*
G03Y0I0J3937D01*
G01X471014Y-15748D02*
G03X463140Y-7874I-7874J0D01*
G01D02*
X459636D01*
G01Y0D02*
G03Y-7874I0J-3937D01*
G01X707234Y-27559D02*
X478888D01*
G01X471014Y-19685D02*
G03X478888Y-27559I7874J0D01*
G01X471014Y-19685D02*
Y-15748D01*
G01X870226Y-27559D02*
X732431D01*
G01Y-19685D02*
G03Y-27559I0J-3937D01*
G01X707234D02*
G03Y-19685I0J3937D01*
G01X870226Y-27559D02*
G03Y-19685I1J3937D01*
G01X1072589Y-27559D02*
X895423D01*
G01Y-19685D02*
G03Y-27559I0J-3937D01*
G01X1072589D02*
G03Y-19685I0J3937D01*
G01X1097785D02*
G03Y-27559I1J-3937D01*
G01X1336086Y-8662D02*
X1318701D01*
G03X1314764Y-12599I0J-3937D01*
G01Y-23622D01*
G02X1310827Y-27559I-3937J0D01*
G01X1097785D01*
G01X1336086Y-8662D02*
G03Y-1I0J4330D01*
G01X1361283D02*
G03Y-8662I0J-4330D01*
G01X1407874Y13026D02*
Y-4725D01*
G02X1403937Y-8662I-3937J0D01*
G01X1361283D01*
G01X1403937Y848425D02*
X1375197D01*
G01X1371260Y852362D02*
G03X1375197Y848425I3937J0D01*
G01X1371260Y852362D02*
Y893701D01*
G01X1375197Y897638D02*
G03X1371260Y893701I0J-3937D01*
G01X1375197Y897638D02*
X1425733D01*
G01X1407874Y30709D02*
Y219685D01*
G01X1400000Y30709D02*
G03X1407874I3937J0D01*
G01Y13026D02*
G03X1400000I-3937J-1D01*
G01X1407874Y219685D02*
G03X1400000I-3937J0D01*
G01Y244882D02*
G03X1407874I3937J0D01*
G01Y414173D02*
Y244882D01*
G01Y608661D02*
Y439370D01*
G01X1400000D02*
G03X1407874I3937J0D01*
G01Y414173D02*
G03X1400000I-3937J0D01*
G01X1407874Y608661D02*
G03X1400000I-3937J0D01*
G01Y626378D02*
G03X1407874I3937J0D01*
G01Y795669D02*
Y626378D01*
G01Y795669D02*
G03X1400000I-3937J0D01*
G01Y820866D02*
G03X1407874I3937J0D01*
G01Y844488D02*
Y820866D01*
G01Y844488D02*
G03X1403937Y848425I-3937J0D01*
G01X1429670Y893701D02*
Y-47244D01*
G01X1425733Y-51181D02*
G03X1429670Y-47244I0J3937D01*
G01Y893701D02*
G03X1425733Y897638I-3937J0D01*
G54D17*
X28148Y310872D03*
X28212Y306674D03*
X21800Y424000D03*
X29300Y429000D03*
X30600Y533500D03*
X25100Y720400D03*
X41600Y321400D03*
X36800Y466000D03*
X57400Y470100D03*
Y474200D03*
X63569Y502220D03*
X37300Y484500D03*
X55400Y713000D03*
X97900Y272000D03*
X95607Y281582D03*
X76291Y365075D03*
X76105Y360727D03*
X85700Y360000D03*
X80990Y392665D03*
X93649Y477241D03*
X79569Y513090D03*
X80444Y508831D03*
X92300Y506000D03*
X80444Y504831D03*
X92300Y526500D03*
Y522500D03*
Y530500D03*
X79569Y517090D03*
X92300Y534500D03*
Y518500D03*
Y538500D03*
X80800Y534300D03*
Y538300D03*
X67720Y535931D03*
Y531831D03*
X80300Y606500D03*
X73800Y582000D03*
X79900Y681900D03*
X87500D03*
X75800Y723200D03*
X79600Y753700D03*
Y757900D03*
X107100Y212200D03*
X106100Y230100D03*
X100800Y294900D03*
Y290900D03*
X100490Y319780D03*
X100540Y315650D03*
X100700Y324100D03*
X100600Y328600D03*
X123000Y392300D03*
X99200Y732300D03*
X114800Y756000D03*
X132480Y311214D03*
X154100Y402200D03*
X162627Y447721D03*
X143369Y636620D03*
X133851Y648436D03*
X137200Y727800D03*
X164000Y753400D03*
X156800Y808500D03*
X179139Y450747D03*
X196300Y729500D03*
Y785000D03*
X207749Y143587D03*
X202900Y251000D03*
X213500Y446000D03*
X219800Y469000D03*
Y465000D03*
X209800Y478000D03*
X218300Y486600D03*
X209800Y502000D03*
Y506000D03*
X223950Y491200D03*
X223962Y495300D03*
X209800Y534500D03*
Y542500D03*
Y538500D03*
Y550500D03*
Y570500D03*
X222672Y563994D03*
X248400Y339700D03*
X261529Y334140D03*
X257500Y443300D03*
X277800Y126000D03*
X285340Y149350D03*
X277800Y145500D03*
X294288Y578165D03*
Y583165D03*
Y588665D03*
X309082Y293550D03*
X333100Y318900D03*
X315700Y538300D03*
X344000Y335600D03*
X483260Y13180D03*
X483270Y26720D03*
X483300Y49880D03*
Y73380D03*
X469960Y143008D03*
X490900Y166000D03*
X473000Y393300D03*
X504242Y130547D03*
X535012Y159035D03*
X534925Y163463D03*
X505100Y186500D03*
X550780Y133550D03*
X545999Y291069D03*
X558331Y342980D03*
X581363Y228608D03*
X589763Y211308D03*
X619863Y209608D03*
X627463Y209408D03*
Y217608D03*
X622163Y238108D03*
X627463Y213508D03*
X605000Y348200D03*
X652300Y340100D03*
X659800D03*
X652300Y344600D03*
Y372100D03*
Y376600D03*
X659800D03*
X652300Y367100D03*
Y362100D03*
Y352600D03*
Y348600D03*
X733100Y14000D03*
X735400Y114020D03*
X735380Y109410D03*
X756400Y35100D03*
Y26200D03*
X764200D03*
X753800Y64000D03*
X767500Y74000D03*
X757900Y98800D03*
Y94700D03*
X765500Y129400D03*
Y125300D03*
X797610Y26343D03*
X784200Y74100D03*
X806800Y82400D03*
X806900Y94600D03*
Y98700D03*
X773600Y135200D03*
X827860Y105630D03*
X811725Y123631D03*
Y127631D03*
X860500Y3900D03*
X861800Y28000D03*
Y36000D03*
X862300Y8000D03*
X871300Y52800D03*
X862133Y44034D03*
X904800Y33000D03*
Y29000D03*
Y41000D03*
X900300Y341600D03*
Y363000D03*
Y354000D03*
X927270Y23540D03*
X984717Y18587D03*
X1033621Y26921D03*
X1011778Y49109D03*
X1048786Y11208D03*
X1075776Y18266D03*
X1074300Y68500D03*
X1054660Y69355D03*
X1062483Y48832D03*
X1087300Y500D03*
Y5000D03*
X1086920Y27440D03*
X1087304Y36383D03*
X1086920Y22940D03*
X1087304Y40883D03*
X1086525Y14177D03*
X1086727Y18525D03*
X1244784Y145217D03*
X1246268Y141179D03*
X1310110Y145310D03*
X1310826Y151199D03*
X1289300Y295000D03*
X1325300Y290500D03*
X1317300Y294000D03*
X1363218Y168102D03*
G54D80*
X141060Y243523D03*
X152028D03*
X140907Y255980D03*
X151875D03*
X566079Y264008D03*
Y276308D03*
Y300908D03*
Y288608D03*
X591079Y274408D03*
X602047D03*
X577047Y264008D03*
Y276308D03*
X591079Y299008D03*
X602047D03*
X591079Y286708D03*
X602047D03*
X577047Y300908D03*
Y288608D03*
X1334016Y192500D03*
X1344984D03*
X1334016Y205000D03*
X1344984D03*
X1334016Y230000D03*
X1344984D03*
X1334016Y217500D03*
X1344984D03*
X1369484Y203500D03*
X1358516D03*
X1369484Y217000D03*
X1358516D03*
X1369484Y230500D03*
X1358516D03*
G54D53*
X54300Y734900D03*
X633000Y356600D03*
G54D44*
X49866Y364307D03*
X44866D03*
X39866D03*
X34866D03*
Y384307D03*
X39866D03*
X44866D03*
X49866D03*
X191018Y211856D03*
X196018D03*
Y239356D03*
X191018D03*
X201018Y211856D03*
X206018D03*
Y239356D03*
X201018D03*
X236231Y245705D03*
X241231D03*
X246231D03*
X251231D03*
X256231D03*
X261231D03*
X266231D03*
Y282855D03*
X261231D03*
X256231D03*
X251231D03*
X246231D03*
X241231D03*
X236231D03*
X271231Y245705D03*
Y282855D03*
X302834Y245636D03*
X307834D03*
X312834D03*
X317834D03*
X322834D03*
X327834D03*
X332834D03*
Y282786D03*
X327834D03*
X322834D03*
X317834D03*
X312834D03*
X307834D03*
X302834D03*
X337834Y245636D03*
Y282786D03*
X519526Y251011D03*
X524526D03*
X529526D03*
X534526D03*
Y278511D03*
X529526D03*
X524526D03*
X519526D03*
G54D62*
X91750Y600560D03*
Y595440D03*
X85250D03*
Y598000D03*
Y600560D03*
X105896Y362064D03*
Y359504D03*
Y356944D03*
X112396D03*
Y362064D03*
X297512Y470240D03*
Y472800D03*
Y475360D03*
X291012D03*
Y470240D03*
X743250Y28640D03*
Y33760D03*
X749750D03*
Y31200D03*
Y28640D03*
G54D26*
X25500Y420000D03*
X20025Y435203D03*
X29400Y738500D03*
X24000Y751200D03*
X46000Y292100D03*
X45882Y287141D03*
X41300Y307200D03*
X62900Y322300D03*
X56500Y372900D03*
X34866Y390400D03*
X64800Y383400D03*
X60500Y439500D03*
X47500Y414000D03*
X60500Y417500D03*
X49000Y469400D03*
X59000Y454500D03*
X60810Y478441D03*
X31562Y465195D03*
X44000Y466500D03*
X31700Y481100D03*
X43046Y497465D03*
X59587Y511198D03*
X42534Y490525D03*
X63370Y498214D03*
X44500Y484000D03*
X52000Y501500D03*
Y484000D03*
X39616Y532255D03*
X64500Y615500D03*
X32498Y682487D03*
X61505Y689980D03*
X34831Y727839D03*
X34300Y732900D03*
X48700Y718195D03*
X35300Y738400D03*
X53700Y717250D03*
X42600Y718000D03*
X34800Y721900D03*
X37800Y745400D03*
X40200Y756200D03*
X35000Y756400D03*
X56100Y755900D03*
X50900Y756000D03*
X64400Y751800D03*
X45400Y756200D03*
X61300D03*
X90100Y266400D03*
X83300Y266800D03*
X75800Y269600D03*
X70000Y273000D03*
X80358Y274360D03*
X96677Y285294D03*
X94700Y335600D03*
X91300Y331600D03*
X96107Y324781D03*
X97838Y311989D03*
X96500Y316900D03*
X98400Y332400D03*
X85800Y355000D03*
X90093Y365200D03*
X67000Y377500D03*
X65965Y362838D03*
X84400Y406500D03*
X93314Y466166D03*
X88500Y509613D03*
X66473Y511404D03*
X73787Y522705D03*
X88727Y547047D03*
X88000Y538500D03*
X93100Y543638D03*
X71540Y518238D03*
X83600Y525700D03*
X81523Y521151D03*
X66494Y556916D03*
X88271Y552998D03*
X98008Y548438D03*
X96537Y555253D03*
X93400Y551200D03*
X65780Y586777D03*
X67508Y608289D03*
X83562Y610519D03*
X92000Y605500D03*
X78200Y646000D03*
X89600Y622600D03*
X73717Y632517D03*
X84000Y615500D03*
X85500Y706800D03*
X70700Y714000D03*
X85000Y714900D03*
X73800Y749600D03*
X71000Y719200D03*
X89600Y727900D03*
X73400Y741700D03*
X73900Y755200D03*
X111319Y195688D03*
X105300Y207900D03*
X111050Y207700D03*
X116300Y218100D03*
X128015Y219803D03*
X100688Y224517D03*
X107300Y272700D03*
X104000Y286200D03*
X124300Y305300D03*
X108385Y327857D03*
X131500Y340800D03*
X122963Y377696D03*
X119830Y348670D03*
X109285Y352411D03*
X130280Y389720D03*
X129694Y379247D03*
X112250Y385000D03*
X100400Y392184D03*
X130000Y397000D03*
X127633Y441705D03*
X131355Y437004D03*
X116300Y436400D03*
X120500Y461000D03*
X125500Y466000D03*
X128500Y456000D03*
X120680Y466020D03*
X102032Y475274D03*
X100000Y462700D03*
X115673Y464911D03*
X106983Y465035D03*
X111421Y467542D03*
X129076Y462500D03*
X107000Y472700D03*
X122406Y447830D03*
X102000Y497700D03*
X105045Y505292D03*
X107423Y500672D03*
X106258Y480600D03*
X99800Y511851D03*
X106000Y511600D03*
X99820Y505670D03*
X103313Y531239D03*
X99829Y527520D03*
X103100Y517400D03*
X103289Y523893D03*
X99476Y534446D03*
X103300Y537800D03*
X99164Y540611D03*
X103000Y555500D03*
X131500Y584000D03*
X104000Y627000D03*
X102020Y633720D03*
X119650Y707800D03*
X101800Y737200D03*
X102100Y723300D03*
X124800Y745300D03*
X120500Y752100D03*
X118600Y762500D03*
X98800Y764900D03*
X125900Y785000D03*
X119800Y813700D03*
X109500Y836500D03*
X162500Y222000D03*
X144300Y235400D03*
X137200Y302300D03*
X145300Y302200D03*
X136257Y316125D03*
X145168Y317749D03*
X137768Y322641D03*
X145965Y374500D03*
X160850Y375200D03*
X138905Y368565D03*
X148900Y363200D03*
X160303Y365303D03*
X151760Y372214D03*
X157065Y395331D03*
X160204Y384199D03*
X137778Y401708D03*
X161800Y389700D03*
X132778Y401706D03*
X134768Y429438D03*
X133812Y414712D03*
X143073Y424833D03*
X164222Y457919D03*
X134090Y465780D03*
X138930Y465660D03*
X141500Y461400D03*
X158790Y458450D03*
X160300Y465900D03*
X164268Y462983D03*
X154700Y461100D03*
X154500Y466000D03*
X150174Y458541D03*
X149461Y466837D03*
X144520Y466070D03*
X163225Y720683D03*
X139642Y736317D03*
X139480Y724027D03*
X149241Y740242D03*
X156126Y775783D03*
X163600Y757500D03*
X156400Y812800D03*
X142492Y795526D03*
X166890Y237540D03*
X182604Y442854D03*
X192173Y466075D03*
X179599Y457479D03*
X170192Y465776D03*
X175000Y466000D03*
X177377Y461749D03*
X180000Y466000D03*
X168320Y455278D03*
X185200Y466000D03*
X198274Y473078D03*
X199510Y465568D03*
X197228Y478071D03*
X189275Y470882D03*
X169399Y470740D03*
X199829Y485947D03*
X198279Y496230D03*
X198223Y509744D03*
X197126Y490845D03*
X198803Y501591D03*
X198000Y529500D03*
Y534500D03*
Y523000D03*
X196882Y542190D03*
X176500Y571500D03*
X174500Y561500D03*
X178500Y576376D03*
X174500Y566500D03*
X193610Y578880D03*
X175360Y580890D03*
X177187Y586239D03*
X187750Y584750D03*
X187500Y596000D03*
X195788Y696965D03*
X175505Y720797D03*
X195900Y733400D03*
X181873Y716530D03*
X189913Y736842D03*
X169029Y775496D03*
X195489Y752261D03*
X175300Y757500D03*
X182092Y771758D03*
X168100Y812800D03*
X195900Y789200D03*
X177092Y800861D03*
X231270Y140880D03*
X203740Y144334D03*
X214145Y147841D03*
X212000Y158300D03*
X205601Y426212D03*
X217998Y424771D03*
X202270Y438448D03*
X202652Y432259D03*
X220969Y431372D03*
X204700Y479804D03*
X204198Y474804D03*
X204500Y490000D03*
X202064Y512946D03*
X221152Y499246D03*
X203000Y534500D03*
X200217Y517593D03*
X217163Y523586D03*
X233101Y526064D03*
X204200Y522600D03*
X203314Y527894D03*
X208500Y563500D03*
X200000Y550424D03*
X202610Y563580D03*
X230856Y566468D03*
X204100Y600100D03*
X230250Y593750D03*
Y582400D03*
X207977Y696708D03*
X221200Y712250D03*
X207600Y733500D03*
X207931Y752312D03*
X218080Y771407D03*
X207600Y789200D03*
X242634Y134760D03*
X248992Y130867D03*
X233770Y152909D03*
X263068Y328619D03*
X252250Y343500D03*
X262604Y350015D03*
X247901Y422389D03*
X241800Y426300D03*
X266756Y431549D03*
X261349Y450988D03*
X249311Y450950D03*
X257000Y473400D03*
X265800Y467660D03*
Y485000D03*
X249601Y514174D03*
X249674Y532413D03*
X237779Y528680D03*
X235291Y521326D03*
X257000Y585500D03*
X248100Y622000D03*
X245050Y647100D03*
X243000Y737500D03*
X240275Y731000D03*
X246000Y745500D03*
X278909Y141324D03*
X280050Y149350D03*
X288000Y193000D03*
X299296Y327204D03*
X300300Y340501D03*
X274702Y365240D03*
X296940Y458370D03*
X296000Y497500D03*
X278100Y482000D03*
X293000Y625700D03*
X282500Y647700D03*
X270700Y627300D03*
X270800Y652900D03*
X280498Y726806D03*
X292831Y729494D03*
X279500Y764500D03*
X274406Y763500D03*
X273700Y752000D03*
X296500Y763000D03*
X290400Y763672D03*
X296872Y821628D03*
X295592Y828408D03*
X329894Y334794D03*
X329000Y320600D03*
X312430Y333540D03*
X304100Y336301D03*
X314485Y352315D03*
X328000Y663000D03*
X304416Y728698D03*
X310622Y760126D03*
X307000Y764000D03*
X303266Y825234D03*
X356361Y158609D03*
X351605Y334920D03*
X353000Y320300D03*
X354500Y325200D03*
X339149Y315170D03*
X344836Y314844D03*
X461900Y73800D03*
X455300Y90600D03*
X464692Y114063D03*
X455328Y159738D03*
X458029Y380305D03*
X465600Y428000D03*
X456100Y727000D03*
X486750Y31020D03*
X486979Y8837D03*
X486760Y54580D03*
X470200Y73800D03*
X478400D03*
X486764Y78077D03*
X474362Y130750D03*
X481800Y131719D03*
X488838Y140700D03*
X475567Y136564D03*
X475089Y114652D03*
X470047Y113969D03*
X497530Y144850D03*
X481801Y329085D03*
X488109Y332641D03*
X488009Y340441D03*
X484695Y360571D03*
X471852Y360377D03*
X484300Y397550D03*
X472600D03*
X494908Y379870D03*
X484830Y780711D03*
X493408Y778813D03*
X502044Y765135D03*
X493255Y816854D03*
X488255Y816894D03*
X487000Y801500D03*
X527293Y345998D03*
X520672Y345868D03*
X509246Y781700D03*
X519458Y779247D03*
X509855Y814998D03*
X520781Y816463D03*
X503745Y815682D03*
X534543Y829543D03*
X532217Y839013D03*
X561600Y154800D03*
X558100Y158600D03*
X538500Y154900D03*
X554074Y291069D03*
X551926Y295585D03*
X549000Y318500D03*
X565900Y339000D03*
X541400Y368580D03*
X548928Y347157D03*
X554500Y380500D03*
X540200Y837200D03*
X591571Y206500D03*
X573151Y211067D03*
X584522Y240830D03*
X571600Y324400D03*
X573500Y381000D03*
X637063Y229408D03*
X632449Y224622D03*
X638063Y290608D03*
X632000Y329100D03*
X620200Y335900D03*
X626260Y341091D03*
X608090Y338070D03*
X632750Y341033D03*
X632600Y372042D03*
X632000Y384100D03*
X637000D03*
X626900Y390900D03*
X613400Y387000D03*
X636150Y400100D03*
X628148Y805648D03*
X614444Y800544D03*
X638470Y807070D03*
X671000Y215000D03*
X660100Y344600D03*
X647621Y340950D03*
X660500Y367100D03*
Y362300D03*
Y372100D03*
X648500Y372000D03*
X642000Y384100D03*
X682000Y174300D03*
X674100Y191500D03*
X688200Y191200D03*
X685000Y215000D03*
X694500Y366000D03*
X713332Y1831D03*
X736317Y35906D03*
X732837Y9562D03*
X723740Y9594D03*
X718343Y10856D03*
X717325Y28240D03*
X738220Y68350D03*
X718500Y68500D03*
X756565Y30918D03*
X763400Y35200D03*
X760084Y53800D03*
X758000Y68500D03*
X742367Y57852D03*
X763147Y65169D03*
X767450Y68465D03*
X766000Y85700D03*
X766683Y99583D03*
X766000Y94400D03*
X768700Y139100D03*
X767600Y117400D03*
X751300Y115000D03*
X745000Y733500D03*
X774392Y69785D03*
X779752Y70067D03*
X773617Y104731D03*
X802600Y89500D03*
X786200Y136200D03*
X805247Y123218D03*
X815200Y7500D03*
X813214Y38497D03*
X824118Y55116D03*
X839289Y68301D03*
X835492Y72992D03*
X835500Y100500D03*
X816600Y83025D03*
X822035Y130312D03*
X811202Y139324D03*
X807900Y114800D03*
X807801Y127889D03*
X833086Y743052D03*
X830569Y751931D03*
X828394Y760106D03*
X865500Y-824D03*
X854453Y3932D03*
X868819Y27276D03*
X869250Y39909D03*
X869195Y34816D03*
X869250Y45400D03*
X863500Y59400D03*
X848781Y64281D03*
X844212Y69179D03*
X842300Y63300D03*
X856000Y62500D03*
X842707Y75879D03*
X861310Y122608D03*
X846730Y123128D03*
X854510Y122640D03*
X847710Y110570D03*
X867000Y357000D03*
X854749Y692148D03*
X864000Y758000D03*
X855292Y782500D03*
X872244Y755738D03*
X863374Y792846D03*
X858000Y794000D03*
X873700Y792100D03*
X901000Y34000D03*
Y29000D03*
Y42000D03*
X878992Y61508D03*
X903000Y61500D03*
X906200Y85270D03*
X896500Y342500D03*
X898817Y311761D03*
X887500Y312000D03*
X896200Y358300D03*
X896500Y350200D03*
X879816Y755877D03*
X888087Y758068D03*
X894108Y790279D03*
X898700Y788300D03*
X879696Y792164D03*
X890049Y793216D03*
X928398Y70962D03*
X940377Y81913D03*
X922015Y83123D03*
X929060Y82741D03*
X934779Y82801D03*
X915908Y83067D03*
X910754Y81409D03*
X937400Y76700D03*
X925300Y78500D03*
X950120Y63525D03*
X942500Y102500D03*
X947000Y106000D03*
X953000Y108000D03*
X960522Y89645D03*
X945590Y82830D03*
X950970Y82791D03*
X956313Y81319D03*
X992540Y18675D03*
X992002Y37056D03*
X1000480Y41812D03*
X1004765Y49647D03*
X1033747Y20176D03*
X1036692Y38477D03*
X1028900Y56100D03*
X1028815Y41714D03*
X1042600Y46100D03*
X1026500Y75500D03*
X1031400Y112500D03*
X1069131Y7363D03*
X1071559Y35329D03*
X1043650Y15633D03*
X1045000Y64500D03*
X1060000Y74000D03*
X1049500Y45000D03*
X1050216Y50022D03*
X1051850Y75550D03*
X1057431Y89182D03*
X1071330Y132580D03*
X1097000Y1500D03*
X1083235Y5000D03*
X1086613Y31774D03*
X1090929Y9074D03*
X1078000Y72500D03*
X1120205Y239021D03*
X1127500Y234500D03*
X1134187Y238517D03*
X1141500Y234000D03*
X1155000Y242000D03*
X1156000Y234500D03*
X1167500Y294500D03*
X1172500Y742500D03*
X1169000Y750500D03*
X1165375Y757000D03*
X1189600Y244600D03*
X1220164Y204033D03*
X1257500Y378500D03*
X1262600Y346000D03*
X1269940D03*
X1278000Y385500D03*
X1273400Y383500D03*
X1268400Y386100D03*
X1266513Y397500D03*
X1261600Y386500D03*
X1273500Y448500D03*
X1299933Y129548D03*
X1305710Y144320D03*
X1295600Y305182D03*
X1285760Y347120D03*
X1284000Y604000D03*
X1311017Y673086D03*
X1306623Y722399D03*
X1301625Y722567D03*
X1314930Y126650D03*
X1319875Y135104D03*
X1316049Y120821D03*
X1329618Y135248D03*
X1325161Y279162D03*
X1329579Y672408D03*
X1316216Y673308D03*
X1333052Y686020D03*
X1319500Y726000D03*
Y737000D03*
Y731500D03*
X1329500Y721500D03*
X1378998Y168228D03*
X1371541Y166287D03*
X1362239Y262939D03*
X1356400Y282400D03*
X1350186Y280040D03*
X1348669Y704831D03*
X1383108Y198473D03*
X1383340Y177216D03*
G54D128*
X876378Y129921D03*
Y133858D03*
Y141732D03*
X880315Y129921D03*
Y133858D03*
Y137795D03*
Y141732D03*
X884252Y129921D03*
Y133858D03*
Y137795D03*
Y141732D03*
X888189Y118110D03*
Y122047D03*
Y125984D03*
Y129921D03*
Y133858D03*
Y137795D03*
Y141732D03*
X892126Y122047D03*
Y125984D03*
Y129921D03*
Y133858D03*
Y137795D03*
Y141732D03*
X896063Y118110D03*
Y122047D03*
Y125984D03*
Y129921D03*
Y133858D03*
Y137795D03*
Y141732D03*
X900000Y122047D03*
Y125984D03*
Y129921D03*
Y133858D03*
Y137795D03*
Y141732D03*
X903937Y118110D03*
Y122047D03*
Y125984D03*
Y129921D03*
Y133858D03*
Y137795D03*
Y141732D03*
X907874Y118110D03*
Y122047D03*
Y125984D03*
Y129921D03*
Y133858D03*
Y137795D03*
Y141732D03*
X876378Y149606D03*
Y157480D03*
Y165354D03*
Y169291D03*
X880315Y145669D03*
Y149606D03*
Y153543D03*
Y157480D03*
Y161417D03*
Y165354D03*
Y169291D03*
Y173228D03*
X884252Y145669D03*
Y149606D03*
Y153543D03*
Y157480D03*
Y161417D03*
Y165354D03*
Y169291D03*
Y173228D03*
X888189Y145669D03*
Y149606D03*
Y153543D03*
Y157480D03*
Y161417D03*
Y165354D03*
Y169291D03*
Y173228D03*
X892126Y145669D03*
Y149606D03*
Y153543D03*
Y157480D03*
Y161417D03*
Y165354D03*
Y169291D03*
Y173228D03*
X896063Y145669D03*
Y149606D03*
Y153543D03*
Y157480D03*
Y161417D03*
Y165354D03*
Y169291D03*
Y173228D03*
X900000Y145669D03*
Y149606D03*
Y153543D03*
Y157480D03*
Y161417D03*
Y165354D03*
Y169291D03*
Y173228D03*
X903937Y145669D03*
Y149606D03*
Y153543D03*
Y157480D03*
Y161417D03*
Y165354D03*
Y169291D03*
Y173228D03*
X907874Y145669D03*
Y149606D03*
Y153543D03*
Y157480D03*
Y161417D03*
Y165354D03*
Y169291D03*
Y173228D03*
X876378Y177165D03*
Y185039D03*
Y192913D03*
Y200787D03*
Y204724D03*
X880315Y177165D03*
Y181102D03*
Y185039D03*
Y188976D03*
Y192913D03*
Y196850D03*
Y200787D03*
Y204724D03*
Y208661D03*
X884252Y177165D03*
Y181102D03*
Y185039D03*
Y188976D03*
Y192913D03*
Y196850D03*
Y200787D03*
Y204724D03*
Y208661D03*
X888189Y177165D03*
Y181102D03*
Y185039D03*
Y188976D03*
Y192913D03*
Y196850D03*
Y200787D03*
Y204724D03*
Y208661D03*
X892126Y177165D03*
Y181102D03*
Y185039D03*
Y188976D03*
Y192913D03*
Y196850D03*
Y200787D03*
Y204724D03*
Y208661D03*
X896063Y177165D03*
Y181102D03*
Y185039D03*
Y188976D03*
Y192913D03*
Y196850D03*
Y200787D03*
Y204724D03*
Y208661D03*
X900000Y177165D03*
Y181102D03*
Y185039D03*
Y188976D03*
Y192913D03*
Y196850D03*
Y200787D03*
Y204724D03*
Y208661D03*
X903937Y177165D03*
Y181102D03*
Y185039D03*
Y188976D03*
Y192913D03*
Y196850D03*
Y200787D03*
Y204724D03*
Y208661D03*
X907874Y177165D03*
Y181102D03*
Y185039D03*
Y188976D03*
Y192913D03*
Y196850D03*
Y200787D03*
Y204724D03*
Y208661D03*
X876378Y212598D03*
Y220472D03*
Y228346D03*
Y236220D03*
Y240157D03*
X880315Y212598D03*
Y216535D03*
Y220472D03*
Y224409D03*
Y228346D03*
Y232283D03*
Y236220D03*
Y240157D03*
X884252Y212598D03*
Y216535D03*
Y220472D03*
Y224409D03*
Y228346D03*
Y232283D03*
Y236220D03*
Y240157D03*
X888189Y212598D03*
Y216535D03*
Y220472D03*
Y224409D03*
Y228346D03*
Y232283D03*
Y236220D03*
Y240157D03*
X892126Y212598D03*
Y216535D03*
Y220472D03*
Y224409D03*
Y228346D03*
Y232283D03*
Y236220D03*
Y240157D03*
X896063Y212598D03*
Y216535D03*
Y220472D03*
Y224409D03*
Y228346D03*
Y232283D03*
Y236220D03*
Y240157D03*
X900000Y212598D03*
Y216535D03*
Y220472D03*
Y224409D03*
Y228346D03*
Y232283D03*
Y236220D03*
Y240157D03*
X903937Y212598D03*
Y216535D03*
Y220472D03*
Y224409D03*
Y228346D03*
Y232283D03*
Y236220D03*
Y240157D03*
X907874Y212598D03*
Y216535D03*
Y220472D03*
Y224409D03*
Y228346D03*
Y232283D03*
Y236220D03*
Y240157D03*
X876378Y244094D03*
Y248031D03*
X880315Y244094D03*
Y248031D03*
X884252Y244094D03*
Y248031D03*
X888189Y244094D03*
Y248031D03*
Y251968D03*
Y255905D03*
Y259842D03*
X892126Y244094D03*
Y248031D03*
Y251968D03*
Y255905D03*
X896063Y244094D03*
Y248031D03*
Y251968D03*
Y255905D03*
Y259842D03*
X900000Y244094D03*
Y248031D03*
Y251968D03*
Y255905D03*
X903937Y244094D03*
Y248031D03*
Y251968D03*
Y255905D03*
Y259842D03*
X907874Y244094D03*
Y248031D03*
Y251968D03*
Y255905D03*
X911811Y122047D03*
Y125984D03*
Y129921D03*
Y133858D03*
Y137795D03*
Y141732D03*
X915748Y118110D03*
Y122047D03*
Y125984D03*
Y129921D03*
Y133858D03*
Y137795D03*
Y141732D03*
X919685Y122047D03*
Y125984D03*
Y129921D03*
Y133858D03*
Y137795D03*
Y141732D03*
X923622Y118110D03*
Y122047D03*
Y125984D03*
Y129921D03*
Y133858D03*
Y137795D03*
Y141732D03*
X927559Y122047D03*
Y125984D03*
Y129921D03*
Y133858D03*
Y137795D03*
Y141732D03*
X931496Y118110D03*
Y122047D03*
Y125984D03*
Y129921D03*
Y133858D03*
Y137795D03*
Y141732D03*
X935433Y122047D03*
Y125984D03*
Y129921D03*
Y133858D03*
Y137795D03*
Y141732D03*
X939370Y118110D03*
Y122047D03*
Y125984D03*
Y129921D03*
Y133858D03*
Y137795D03*
Y141732D03*
X911811Y145669D03*
Y149606D03*
Y153543D03*
Y157480D03*
Y161417D03*
Y165354D03*
Y169291D03*
Y173228D03*
X915748Y145669D03*
Y149606D03*
Y153543D03*
Y157480D03*
Y161417D03*
Y165354D03*
Y169291D03*
Y173228D03*
X919685Y145669D03*
Y149606D03*
Y153543D03*
Y157480D03*
Y161417D03*
Y165354D03*
Y169291D03*
Y173228D03*
X923622Y145669D03*
Y149606D03*
Y153543D03*
Y157480D03*
Y161417D03*
Y165354D03*
Y169291D03*
Y173228D03*
X927559Y145669D03*
Y149606D03*
Y153543D03*
Y157480D03*
Y161417D03*
Y165354D03*
Y169291D03*
Y173228D03*
X931496Y145669D03*
Y149606D03*
Y153543D03*
Y157480D03*
Y161417D03*
Y165354D03*
Y169291D03*
Y173228D03*
X935433Y145669D03*
Y149606D03*
Y153543D03*
Y157480D03*
Y161417D03*
Y165354D03*
Y169291D03*
Y173228D03*
X939370Y145669D03*
Y149606D03*
Y153543D03*
Y157480D03*
Y161417D03*
Y165354D03*
Y169291D03*
Y173228D03*
X911811Y177165D03*
Y181102D03*
Y185039D03*
Y188976D03*
Y192913D03*
Y196850D03*
Y200787D03*
Y204724D03*
Y208661D03*
X915748Y177165D03*
Y181102D03*
Y185039D03*
Y188976D03*
Y192913D03*
Y196850D03*
Y200787D03*
Y204724D03*
Y208661D03*
X919685Y177165D03*
Y181102D03*
Y185039D03*
Y188976D03*
Y192913D03*
Y196850D03*
Y200787D03*
Y204724D03*
Y208661D03*
X923622Y177165D03*
Y181102D03*
Y185039D03*
Y188976D03*
Y192913D03*
Y196850D03*
Y200787D03*
Y204724D03*
Y208661D03*
X927559Y177165D03*
Y181102D03*
Y185039D03*
Y188976D03*
Y192913D03*
Y196850D03*
Y200787D03*
Y204724D03*
Y208661D03*
X931496Y177165D03*
Y181102D03*
Y185039D03*
Y188976D03*
Y192913D03*
Y196850D03*
Y200787D03*
Y204724D03*
Y208661D03*
X935433Y177165D03*
Y181102D03*
Y185039D03*
Y188976D03*
Y192913D03*
Y196850D03*
Y200787D03*
Y204724D03*
Y208661D03*
X939370Y177165D03*
Y181102D03*
Y185039D03*
Y188976D03*
Y192913D03*
Y196850D03*
Y200787D03*
Y204724D03*
Y208661D03*
X911811Y212598D03*
Y216535D03*
Y220472D03*
Y224409D03*
Y228346D03*
Y232283D03*
Y236220D03*
Y240157D03*
X915748Y212598D03*
Y216535D03*
Y220472D03*
Y224409D03*
Y228346D03*
Y232283D03*
Y236220D03*
Y240157D03*
X919685Y212598D03*
Y216535D03*
Y220472D03*
Y224409D03*
Y228346D03*
Y232283D03*
Y236220D03*
Y240157D03*
X923622Y212598D03*
Y216535D03*
Y220472D03*
Y224409D03*
Y228346D03*
Y232283D03*
Y236220D03*
Y240157D03*
X927559Y212598D03*
Y216535D03*
Y220472D03*
Y224409D03*
Y228346D03*
Y232283D03*
Y236220D03*
Y240157D03*
X931496Y212598D03*
Y216535D03*
Y220472D03*
Y224409D03*
Y228346D03*
Y232283D03*
Y236220D03*
Y240157D03*
X935433Y212598D03*
Y216535D03*
Y220472D03*
Y224409D03*
Y228346D03*
Y232283D03*
Y236220D03*
Y240157D03*
X939370Y212598D03*
Y216535D03*
Y220472D03*
Y224409D03*
Y228346D03*
Y232283D03*
Y236220D03*
Y240157D03*
X911811Y244094D03*
Y248031D03*
Y251968D03*
Y255905D03*
Y259842D03*
X915748Y244094D03*
Y248031D03*
Y251968D03*
Y255905D03*
Y259842D03*
X919685Y244094D03*
Y248031D03*
Y251968D03*
Y255905D03*
X923622Y244094D03*
Y248031D03*
Y251968D03*
Y255905D03*
Y259842D03*
X927559Y244094D03*
Y248031D03*
Y251968D03*
Y255905D03*
X931496Y244094D03*
Y248031D03*
Y251968D03*
Y255905D03*
Y259842D03*
X935433Y244094D03*
Y248031D03*
Y251968D03*
Y255905D03*
X939370Y244094D03*
Y248031D03*
Y251968D03*
Y255905D03*
Y259842D03*
X943307Y118110D03*
Y122047D03*
Y125984D03*
Y129921D03*
Y133858D03*
Y137795D03*
Y141732D03*
X947244Y118110D03*
Y122047D03*
Y125984D03*
Y129921D03*
Y133858D03*
Y137795D03*
Y141732D03*
X951181Y118110D03*
Y122047D03*
Y125984D03*
Y129921D03*
Y133858D03*
Y137795D03*
Y141732D03*
X955118Y118110D03*
Y122047D03*
Y125984D03*
Y129921D03*
Y133858D03*
Y137795D03*
Y141732D03*
X959055Y122047D03*
Y125984D03*
Y129921D03*
Y133858D03*
Y137795D03*
Y141732D03*
X962992Y118110D03*
Y122047D03*
Y125984D03*
Y129921D03*
Y133858D03*
Y137795D03*
Y141732D03*
X966929Y122047D03*
Y125984D03*
Y129921D03*
Y133858D03*
Y137795D03*
Y141732D03*
X970866Y118110D03*
Y122047D03*
Y125984D03*
Y129921D03*
Y133858D03*
Y137795D03*
Y141732D03*
X974803Y122047D03*
Y125984D03*
Y129921D03*
Y133858D03*
Y137795D03*
Y141732D03*
X943307Y145669D03*
Y149606D03*
Y153543D03*
Y157480D03*
Y161417D03*
Y165354D03*
Y169291D03*
Y173228D03*
X947244Y145669D03*
Y149606D03*
Y153543D03*
Y157480D03*
Y161417D03*
Y165354D03*
Y169291D03*
Y173228D03*
X951181Y145669D03*
Y149606D03*
Y153543D03*
Y157480D03*
Y161417D03*
Y165354D03*
Y169291D03*
Y173228D03*
X955118Y145669D03*
Y149606D03*
Y153543D03*
Y157480D03*
Y161417D03*
Y165354D03*
Y169291D03*
Y173228D03*
X959055Y145669D03*
Y149606D03*
Y153543D03*
Y157480D03*
Y161417D03*
Y165354D03*
Y169291D03*
Y173228D03*
X962992Y145669D03*
Y149606D03*
Y153543D03*
Y157480D03*
Y161417D03*
Y165354D03*
Y169291D03*
Y173228D03*
X966929Y145669D03*
Y149606D03*
Y153543D03*
Y157480D03*
Y161417D03*
Y165354D03*
Y169291D03*
Y173228D03*
X970866Y145669D03*
Y149606D03*
Y153543D03*
Y157480D03*
Y161417D03*
Y165354D03*
Y169291D03*
Y173228D03*
X974803Y145669D03*
Y149606D03*
Y153543D03*
Y157480D03*
Y161417D03*
Y165354D03*
Y169291D03*
Y173228D03*
X943307Y177165D03*
Y181102D03*
Y185039D03*
Y188976D03*
Y192913D03*
Y196850D03*
Y200787D03*
Y204724D03*
Y208661D03*
X947244Y177165D03*
Y181102D03*
Y185039D03*
Y188976D03*
Y192913D03*
Y196850D03*
Y200787D03*
Y204724D03*
Y208661D03*
X951181Y177165D03*
Y181102D03*
Y185039D03*
Y188976D03*
Y192913D03*
Y196850D03*
Y200787D03*
Y204724D03*
Y208661D03*
X955118Y177165D03*
Y181102D03*
Y185039D03*
Y188976D03*
Y192913D03*
Y196850D03*
Y200787D03*
Y204724D03*
Y208661D03*
X959055Y177165D03*
Y181102D03*
Y185039D03*
Y188976D03*
Y192913D03*
Y196850D03*
Y200787D03*
Y204724D03*
Y208661D03*
X962992Y177165D03*
Y181102D03*
Y185039D03*
Y188976D03*
Y192913D03*
Y196850D03*
Y200787D03*
Y204724D03*
Y208661D03*
X966929Y177165D03*
Y181102D03*
Y185039D03*
Y188976D03*
Y192913D03*
Y196850D03*
Y200787D03*
Y204724D03*
Y208661D03*
X970866Y177165D03*
Y181102D03*
Y185039D03*
Y188976D03*
Y192913D03*
Y196850D03*
Y200787D03*
Y204724D03*
Y208661D03*
X974803Y177165D03*
Y181102D03*
Y185039D03*
Y188976D03*
Y192913D03*
Y196850D03*
Y200787D03*
Y204724D03*
Y208661D03*
X943307Y212598D03*
Y216535D03*
Y220472D03*
Y224409D03*
Y228346D03*
Y232283D03*
Y236220D03*
Y240157D03*
X947244Y212598D03*
Y216535D03*
Y220472D03*
Y224409D03*
Y228346D03*
Y232283D03*
Y236220D03*
Y240157D03*
X951181Y212598D03*
Y216535D03*
Y220472D03*
Y224409D03*
Y228346D03*
Y232283D03*
Y236220D03*
Y240157D03*
X955118Y212598D03*
Y216535D03*
Y220472D03*
Y224409D03*
Y228346D03*
Y232283D03*
Y236220D03*
Y240157D03*
X959055Y212598D03*
Y216535D03*
Y220472D03*
Y224409D03*
Y228346D03*
Y232283D03*
Y236220D03*
Y240157D03*
X962992Y212598D03*
Y216535D03*
Y220472D03*
Y224409D03*
Y228346D03*
Y232283D03*
Y236220D03*
Y240157D03*
X966929Y212598D03*
Y216535D03*
Y220472D03*
Y224409D03*
Y228346D03*
Y232283D03*
Y236220D03*
Y240157D03*
X970866Y212598D03*
Y216535D03*
Y220472D03*
Y224409D03*
Y228346D03*
Y232283D03*
Y236220D03*
Y240157D03*
X974803Y212598D03*
Y216535D03*
Y220472D03*
Y224409D03*
Y228346D03*
Y232283D03*
Y236220D03*
Y240157D03*
X943307Y244094D03*
Y248031D03*
Y251968D03*
Y255905D03*
X947244Y244094D03*
Y248031D03*
Y251968D03*
Y255905D03*
Y259842D03*
X951181Y244094D03*
Y248031D03*
Y251968D03*
Y255905D03*
X955118Y244094D03*
Y248031D03*
Y251968D03*
Y255905D03*
Y259842D03*
X959055Y244094D03*
Y248031D03*
Y251968D03*
Y255905D03*
X962992Y244094D03*
Y248031D03*
Y251968D03*
Y255905D03*
Y259842D03*
X966929Y244094D03*
Y248031D03*
Y251968D03*
Y255905D03*
X970866Y244094D03*
Y248031D03*
Y251968D03*
Y255905D03*
Y259842D03*
X974803Y244094D03*
Y248031D03*
Y251968D03*
Y255905D03*
X978740Y118110D03*
Y122047D03*
Y125984D03*
Y129921D03*
Y133858D03*
Y137795D03*
Y141732D03*
X982677Y122047D03*
Y125984D03*
Y129921D03*
Y133858D03*
Y137795D03*
Y141732D03*
X986614Y118110D03*
Y122047D03*
Y125984D03*
Y129921D03*
Y133858D03*
Y137795D03*
Y141732D03*
X990551Y118110D03*
Y122047D03*
Y125984D03*
Y129921D03*
Y133858D03*
Y137795D03*
Y141732D03*
X994488Y122047D03*
Y125984D03*
Y129921D03*
Y133858D03*
Y137795D03*
Y141732D03*
X998425Y118110D03*
Y122047D03*
Y125984D03*
Y129921D03*
Y133858D03*
Y137795D03*
Y141732D03*
X1002362Y122047D03*
Y125984D03*
Y129921D03*
Y133858D03*
Y137795D03*
Y141732D03*
X1006299Y118110D03*
Y122047D03*
Y125984D03*
Y129921D03*
Y133858D03*
Y137795D03*
Y141732D03*
X978740Y145669D03*
Y149606D03*
Y153543D03*
Y157480D03*
Y161417D03*
Y165354D03*
Y169291D03*
Y173228D03*
X982677Y145669D03*
Y149606D03*
Y153543D03*
Y157480D03*
Y161417D03*
Y165354D03*
Y169291D03*
Y173228D03*
X986614Y145669D03*
Y149606D03*
Y153543D03*
Y157480D03*
Y161417D03*
Y165354D03*
Y169291D03*
Y173228D03*
X990551Y145669D03*
Y149606D03*
Y153543D03*
Y157480D03*
Y161417D03*
Y165354D03*
Y169291D03*
Y173228D03*
X994488Y145669D03*
Y149606D03*
Y153543D03*
Y157480D03*
Y161417D03*
Y165354D03*
Y169291D03*
Y173228D03*
X998425Y145669D03*
Y149606D03*
Y153543D03*
Y157480D03*
Y161417D03*
Y165354D03*
Y169291D03*
Y173228D03*
X1002362Y145669D03*
Y149606D03*
Y153543D03*
Y157480D03*
Y161417D03*
Y165354D03*
Y169291D03*
Y173228D03*
X1006299Y145669D03*
Y149606D03*
Y153543D03*
Y157480D03*
Y161417D03*
Y165354D03*
Y169291D03*
Y173228D03*
X978740Y177165D03*
Y181102D03*
Y185039D03*
Y188976D03*
Y192913D03*
Y196850D03*
Y200787D03*
Y204724D03*
Y208661D03*
X982677Y177165D03*
Y181102D03*
Y185039D03*
Y188976D03*
Y192913D03*
Y196850D03*
Y200787D03*
Y204724D03*
Y208661D03*
X986614Y177165D03*
Y181102D03*
Y185039D03*
Y188976D03*
Y192913D03*
Y196850D03*
Y200787D03*
Y204724D03*
Y208661D03*
X990551Y177165D03*
Y181102D03*
Y185039D03*
Y188976D03*
Y192913D03*
Y196850D03*
Y200787D03*
Y204724D03*
Y208661D03*
X994488Y177165D03*
Y181102D03*
Y185039D03*
Y188976D03*
Y192913D03*
Y196850D03*
Y200787D03*
Y204724D03*
Y208661D03*
X998425Y177165D03*
Y181102D03*
Y185039D03*
Y188976D03*
Y192913D03*
Y196850D03*
Y200787D03*
Y204724D03*
Y208661D03*
X1002362Y177165D03*
Y181102D03*
Y185039D03*
Y188976D03*
Y192913D03*
Y196850D03*
Y200787D03*
Y204724D03*
Y208661D03*
X1006299Y177165D03*
Y181102D03*
Y185039D03*
Y188976D03*
Y192913D03*
Y196850D03*
Y200787D03*
Y204724D03*
Y208661D03*
X978740Y212598D03*
Y216535D03*
Y220472D03*
Y224409D03*
Y228346D03*
Y232283D03*
Y236220D03*
Y240157D03*
X982677Y212598D03*
Y216535D03*
Y220472D03*
Y224409D03*
Y228346D03*
Y232283D03*
Y236220D03*
Y240157D03*
X986614Y212598D03*
Y216535D03*
Y220472D03*
Y224409D03*
Y228346D03*
Y232283D03*
Y236220D03*
Y240157D03*
X990551Y212598D03*
Y216535D03*
Y220472D03*
Y224409D03*
Y228346D03*
Y232283D03*
Y236220D03*
Y240157D03*
X994488Y212598D03*
Y216535D03*
Y220472D03*
Y224409D03*
Y228346D03*
Y232283D03*
Y236220D03*
Y240157D03*
X998425Y212598D03*
Y216535D03*
Y220472D03*
Y224409D03*
Y228346D03*
Y232283D03*
Y236220D03*
Y240157D03*
X1002362Y212598D03*
Y216535D03*
Y220472D03*
Y224409D03*
Y228346D03*
Y232283D03*
Y236220D03*
Y240157D03*
X1006299Y212598D03*
Y216535D03*
Y220472D03*
Y224409D03*
Y228346D03*
Y232283D03*
Y236220D03*
Y240157D03*
X978740Y244094D03*
Y248031D03*
Y251968D03*
Y255905D03*
Y259842D03*
X982677Y244094D03*
Y248031D03*
Y251968D03*
Y255905D03*
Y259842D03*
X986614Y244094D03*
Y248031D03*
Y251968D03*
Y255905D03*
X990551Y244094D03*
Y248031D03*
Y251968D03*
Y255905D03*
Y259842D03*
X994488Y244094D03*
Y248031D03*
Y251968D03*
Y255905D03*
X998425Y244094D03*
Y248031D03*
Y251968D03*
Y255905D03*
Y259842D03*
X1002362Y244094D03*
Y248031D03*
Y251968D03*
Y255905D03*
X1006299Y244094D03*
Y248031D03*
Y251968D03*
Y255905D03*
Y259842D03*
X1010236Y129921D03*
Y133858D03*
Y137795D03*
Y141732D03*
X1014173Y129921D03*
Y133858D03*
Y137795D03*
Y141732D03*
X1018110Y129921D03*
Y133858D03*
Y141732D03*
X1010236Y145669D03*
Y149606D03*
Y153543D03*
Y157480D03*
Y161417D03*
Y165354D03*
Y169291D03*
Y173228D03*
X1014173Y145669D03*
Y149606D03*
Y153543D03*
Y157480D03*
Y161417D03*
Y165354D03*
Y169291D03*
Y173228D03*
X1018110Y149606D03*
Y157480D03*
Y165354D03*
Y169291D03*
X1010236Y177165D03*
Y181102D03*
Y185039D03*
Y188976D03*
Y192913D03*
Y196850D03*
Y200787D03*
Y204724D03*
Y208661D03*
X1014173Y177165D03*
Y181102D03*
Y185039D03*
Y188976D03*
Y192913D03*
Y196850D03*
Y200787D03*
Y204724D03*
Y208661D03*
X1018110Y177165D03*
Y185039D03*
Y192913D03*
Y200787D03*
Y204724D03*
X1010236Y212598D03*
Y216535D03*
Y220472D03*
Y224409D03*
Y228346D03*
Y232283D03*
Y236220D03*
Y240157D03*
X1014173Y212598D03*
Y216535D03*
Y220472D03*
Y224409D03*
Y228346D03*
Y232283D03*
Y236220D03*
Y240157D03*
X1018110Y212598D03*
Y220472D03*
Y228346D03*
Y236220D03*
Y240157D03*
X1010236Y244094D03*
Y248031D03*
X1014173Y244094D03*
Y248031D03*
X1018110Y244094D03*
Y248031D03*
G54D119*
X700939Y212618D03*
X738439D03*
G54D71*
X116948Y512145D03*
X120098D03*
X123247D03*
X126397D03*
X129547D03*
X116948Y508996D03*
X120098D03*
X123247D03*
X126397D03*
X129547D03*
X116948Y505846D03*
X120098D03*
X123247D03*
X126397D03*
X129547D03*
X116948Y502696D03*
X120098D03*
X123247D03*
X126397D03*
X129547D03*
X116948Y499547D03*
X120098D03*
X123247D03*
X126397D03*
X129547D03*
X116948Y496397D03*
X120098D03*
X123247D03*
X126397D03*
X129547D03*
X116948Y493248D03*
X120098D03*
X123247D03*
X126397D03*
X129547D03*
X116948Y490098D03*
X120098D03*
X123247D03*
X126397D03*
X129547D03*
X126397Y486948D03*
X129547D03*
X126397Y483799D03*
X129547D03*
X126397Y480649D03*
X129547D03*
X126397Y546791D03*
X129547D03*
X126397Y543641D03*
X129547D03*
X126397Y540492D03*
X129547D03*
X116948Y537342D03*
X120098D03*
X123247D03*
X126397D03*
X129547D03*
X116948Y534192D03*
X120098D03*
X123247D03*
X126397D03*
X129547D03*
X116948Y531043D03*
X120098D03*
X123247D03*
X126397D03*
X129547D03*
X116948Y527893D03*
X120098D03*
X123247D03*
X126397D03*
X129547D03*
X116948Y524744D03*
X120098D03*
X123247D03*
X126397D03*
X129547D03*
X116948Y521594D03*
X120098D03*
X123247D03*
X126397D03*
X129547D03*
X116948Y518444D03*
X120098D03*
X123247D03*
X126397D03*
X129547D03*
X116948Y515295D03*
X120098D03*
X123247D03*
X126397D03*
X129547D03*
X117197Y593622D03*
Y596771D03*
Y599921D03*
Y612519D03*
X120347Y593622D03*
Y596771D03*
Y599921D03*
Y612519D03*
X123496Y593622D03*
Y596771D03*
Y599921D03*
Y612519D03*
X126646Y593622D03*
Y596771D03*
Y599921D03*
Y612519D03*
X129795Y593622D03*
Y596771D03*
Y599921D03*
Y612519D03*
X117197Y615669D03*
Y618818D03*
X120347Y615669D03*
Y618818D03*
X123496Y615669D03*
Y618818D03*
X126646Y615669D03*
Y618818D03*
X129795Y615669D03*
Y618818D03*
X132696Y512145D03*
X142145D03*
X145295D03*
X148444D03*
X151594D03*
X154743D03*
X157893D03*
X132696Y508996D03*
X142145D03*
X145295D03*
X148444D03*
X151594D03*
X154743D03*
X157893D03*
X132696Y505846D03*
X142145D03*
X145295D03*
X148444D03*
X151594D03*
X154743D03*
X157893D03*
X132696Y502696D03*
X138995Y496397D03*
X142145D03*
X145295D03*
X148444D03*
X151594D03*
X154743D03*
X157893D03*
X161043D03*
X132696Y493248D03*
X135846D03*
X138995D03*
X142145D03*
X145295D03*
X148444D03*
X151594D03*
X154743D03*
X157893D03*
X161043D03*
X164192D03*
X132696Y490098D03*
X135846D03*
X138995D03*
X142145D03*
X145295D03*
X148444D03*
X151594D03*
X154743D03*
X157893D03*
X161043D03*
X164192D03*
X132696Y486948D03*
X135846D03*
X138995D03*
X142145D03*
X145295D03*
X148444D03*
X151594D03*
X154743D03*
X157893D03*
X161043D03*
X164192D03*
X132696Y483799D03*
X135846D03*
X138995D03*
X142145D03*
X145295D03*
X148444D03*
X151594D03*
X154743D03*
X157893D03*
X161043D03*
X164192D03*
X132696Y480649D03*
X135846D03*
X138995D03*
X142145D03*
X145295D03*
X148444D03*
X151594D03*
X154743D03*
X157893D03*
X161043D03*
X164192D03*
X132696Y546791D03*
X135846D03*
X138995D03*
X142145D03*
X145295D03*
X148444D03*
X151594D03*
X154743D03*
X157893D03*
X161043D03*
X164192D03*
X132696Y543641D03*
X135846D03*
X138995D03*
X142145D03*
X145295D03*
X148444D03*
X151594D03*
X154743D03*
X157893D03*
X161043D03*
X164192D03*
X132696Y540492D03*
X135846D03*
X138995D03*
X142145D03*
X145295D03*
X148444D03*
X151594D03*
X154743D03*
X157893D03*
X161043D03*
X164192D03*
X132696Y537342D03*
X135846D03*
X138995D03*
X142145D03*
X145295D03*
X148444D03*
X151594D03*
X154743D03*
X157893D03*
X161043D03*
X164192D03*
X132696Y534192D03*
X135846D03*
X138995D03*
X142145D03*
X145295D03*
X148444D03*
X151594D03*
X154743D03*
X157893D03*
X161043D03*
X164192D03*
X138995Y531043D03*
X142145D03*
X145295D03*
X148444D03*
X151594D03*
X154743D03*
X157893D03*
X161043D03*
X132696Y524744D03*
Y521594D03*
X142145D03*
X145295D03*
X148444D03*
X151594D03*
X154743D03*
X157893D03*
X132696Y518444D03*
X142145D03*
X145295D03*
X148444D03*
X151594D03*
X154743D03*
X157893D03*
X132696Y515295D03*
X142145D03*
X145295D03*
X148444D03*
X151594D03*
X154743D03*
X157893D03*
X132945Y593622D03*
Y596771D03*
Y599921D03*
Y612519D03*
X136095Y593622D03*
Y596771D03*
Y599921D03*
Y612519D03*
X139244Y593622D03*
Y596771D03*
Y599921D03*
Y612519D03*
X142394Y593622D03*
Y596771D03*
Y599921D03*
Y612519D03*
X145543Y593622D03*
Y596771D03*
Y599921D03*
Y612519D03*
X148693Y593622D03*
Y596771D03*
Y599921D03*
Y612519D03*
X151843Y593622D03*
Y596771D03*
Y599921D03*
Y612519D03*
X154992Y593622D03*
Y596771D03*
Y599921D03*
Y612519D03*
X158142Y593622D03*
Y596771D03*
Y599921D03*
Y612519D03*
X161291Y593622D03*
Y596771D03*
Y599921D03*
Y612519D03*
X164441Y593622D03*
Y596771D03*
Y599921D03*
Y612519D03*
X132945Y615669D03*
Y618818D03*
X136095Y615669D03*
Y618818D03*
X139244Y615669D03*
Y618818D03*
X142394Y615669D03*
Y618818D03*
X145543Y615669D03*
Y618818D03*
X148693Y615669D03*
Y618818D03*
X151843Y615669D03*
Y618818D03*
X154992Y615669D03*
Y618818D03*
X158142Y615669D03*
Y618818D03*
X161291Y615669D03*
Y618818D03*
X164441Y615669D03*
Y618818D03*
X167342Y512145D03*
X170491D03*
X173641D03*
X176791D03*
X179940D03*
X183090D03*
X167342Y508996D03*
X170491D03*
X173641D03*
X176791D03*
X179940D03*
X183090D03*
X167342Y505846D03*
X170491D03*
X173641D03*
X176791D03*
X179940D03*
X183090D03*
X167342Y502696D03*
X170491D03*
X173641D03*
X176791D03*
X179940D03*
X183090D03*
X170491Y499547D03*
X173641D03*
X176791D03*
X179940D03*
X183090D03*
X170491Y496397D03*
X173641D03*
X176791D03*
X179940D03*
X183090D03*
X167342Y493248D03*
X170491D03*
X173641D03*
X176791D03*
X179940D03*
X183090D03*
X167342Y490098D03*
X170491D03*
X173641D03*
X176791D03*
X179940D03*
X183090D03*
X167342Y486948D03*
X170491D03*
X173641D03*
X167342Y483799D03*
X170491D03*
X173641D03*
X167342Y480649D03*
X170491D03*
X173641D03*
X167342Y546791D03*
X170491D03*
X173641D03*
X167342Y543641D03*
X170491D03*
X173641D03*
X167342Y540492D03*
X170491D03*
X173641D03*
X167342Y537342D03*
X170491D03*
X173641D03*
X176791D03*
X179940D03*
X183090D03*
X167342Y534192D03*
X170491D03*
X173641D03*
X176791D03*
X179940D03*
X183090D03*
X170491Y531043D03*
X173641D03*
X176791D03*
X179940D03*
X183090D03*
X170491Y527893D03*
X173641D03*
X176791D03*
X179940D03*
X183090D03*
X167342Y524744D03*
X170491D03*
X173641D03*
X176791D03*
X179940D03*
X183090D03*
X167342Y521594D03*
X170491D03*
X173641D03*
X176791D03*
X179940D03*
X183090D03*
X167342Y518444D03*
X170491D03*
X173641D03*
X176791D03*
X179940D03*
X183090D03*
X167342Y515295D03*
X170491D03*
X173641D03*
X176791D03*
X179940D03*
X183090D03*
G54D35*
X37200Y204900D03*
X52550Y200100D03*
X58300Y775300D03*
X87950Y199400D03*
X73400Y204800D03*
X91250Y702150D03*
X159800Y783000D03*
Y804000D03*
X199300Y704000D03*
Y725000D03*
X167000Y727900D03*
Y748900D03*
X199300Y759500D03*
Y780500D03*
X213800Y530000D03*
X291800Y126000D03*
X288500Y630200D03*
X310639Y340501D03*
X312300Y712400D03*
X476000Y367800D03*
Y388800D03*
X529500Y829700D03*
X651700Y814500D03*
X733509Y68898D03*
X713824D03*
X753194D03*
X851734Y-1815D03*
X1175500Y814200D03*
X1302406Y7874D03*
Y31496D03*
Y55118D03*
Y78740D03*
X1304600Y818400D03*
X1346800Y246500D03*
G54D54*
X88276Y248031D03*
G54D63*
X84800Y590300D03*
X121700Y173000D03*
X107500Y203300D03*
X121700Y185000D03*
Y181000D03*
Y177000D03*
Y189000D03*
X104058Y427004D03*
X104062Y430420D03*
X134100Y264300D03*
X141637Y407034D03*
X180800Y289472D03*
X199700Y580500D03*
X209700Y517500D03*
X261429Y338640D03*
X252188Y577665D03*
X241500Y643400D03*
X263500Y647400D03*
X277700Y130000D03*
X287500Y465000D03*
X329658Y292248D03*
X455892Y114254D03*
X558231Y338980D03*
X619563Y221608D03*
X738800Y20300D03*
X713200Y81500D03*
Y78000D03*
Y96500D03*
Y93000D03*
Y105500D03*
Y102000D03*
Y85000D03*
Y88500D03*
Y117500D03*
Y114000D03*
X757400Y109300D03*
Y112800D03*
X802800Y106300D03*
Y102800D03*
X835186Y161691D03*
Y158240D03*
X927200Y27270D03*
X1054600Y44400D03*
X1317200Y290000D03*
G54D129*
X1041108Y1702D03*
X1031265D03*
X1050951D03*
G54D18*
X27470Y330307D03*
Y350307D03*
X43262Y330307D03*
Y350307D03*
G54D81*
X154369Y286183D03*
X140069D03*
G54D90*
X215338Y436405D03*
Y433845D03*
Y431285D03*
X207938Y436405D03*
Y433845D03*
Y431285D03*
X249800Y348840D03*
Y351400D03*
Y353960D03*
X257200Y348840D03*
Y351400D03*
Y353960D03*
X257600Y433160D03*
Y430600D03*
Y428040D03*
X250200Y433160D03*
Y430600D03*
Y428040D03*
X269000Y501360D03*
Y498800D03*
Y496240D03*
X276400D03*
Y498800D03*
Y501360D03*
Y508440D03*
Y511000D03*
X269000D03*
Y508440D03*
X276400Y513560D03*
X269000D03*
G54D45*
X59550Y367033D03*
Y358033D03*
X78500Y615500D03*
X70000D03*
X78500Y624500D03*
X70000D03*
G54D27*
X25000Y527062D03*
X34000D03*
X119500Y768500D03*
X128500D03*
G54D36*
X47700Y204900D03*
X63050Y200100D03*
X43300Y414000D03*
X83900Y204800D03*
X98450Y199400D03*
X85600Y736400D03*
X85700Y749300D03*
X85600Y762400D03*
X118532Y268820D03*
X128500Y761300D03*
Y756300D03*
X145100Y306400D03*
X134600D03*
X145301Y411131D03*
X133100Y835000D03*
X177500Y748900D03*
Y727900D03*
X170300Y783000D03*
Y804000D03*
X215800Y473500D03*
X209800Y704000D03*
Y725000D03*
Y780500D03*
Y759500D03*
X266600Y651900D03*
X348700Y730900D03*
X497288Y7874D03*
Y31496D03*
Y55118D03*
Y78740D03*
X486500Y367800D03*
Y388800D03*
X569331Y384080D03*
X600163Y257608D03*
X658300Y357600D03*
X723563Y-3650D03*
X873152Y741450D03*
X889400Y739800D03*
X890937Y812539D03*
X1068154Y68898D03*
X1048469D03*
X1087839D03*
G54D72*
X116948Y486948D03*
X120098D03*
X123247D03*
X116948Y483799D03*
X120098D03*
X123247D03*
X116948Y480649D03*
X120098D03*
X123247D03*
X116948Y546791D03*
X120098D03*
X123247D03*
X116948Y543641D03*
X120098D03*
X123247D03*
X116948Y540492D03*
X120098D03*
X123247D03*
X176791Y486948D03*
X179940D03*
X183090D03*
X176791Y483799D03*
X179940D03*
X183090D03*
X176791Y480649D03*
X179940D03*
X183090D03*
X176791Y546791D03*
X179940D03*
X183090D03*
X176791Y543641D03*
X179940D03*
X183090D03*
X176791Y540492D03*
X179940D03*
X183090D03*
G54D64*
X88400Y590300D03*
X125300Y173000D03*
X111100Y203300D03*
X125300Y185000D03*
Y181000D03*
Y177000D03*
Y189000D03*
X107658Y427004D03*
X107662Y430420D03*
X137700Y264300D03*
X145237Y407034D03*
X184400Y289472D03*
X213300Y517500D03*
X203300Y580500D03*
X265029Y338640D03*
X255788Y577665D03*
X245100Y643400D03*
X267100Y647400D03*
X281300Y130000D03*
X291100Y465000D03*
X333258Y292248D03*
X459492Y114254D03*
X561831Y338980D03*
X623163Y221608D03*
X716800Y81500D03*
Y78000D03*
Y96500D03*
Y93000D03*
Y105500D03*
Y102000D03*
Y85000D03*
Y88500D03*
Y117500D03*
Y114000D03*
X742400Y20300D03*
X761000Y109300D03*
Y112800D03*
X806400Y106300D03*
Y102800D03*
X838786Y161691D03*
Y158240D03*
X930800Y27270D03*
X1058200Y44400D03*
X1320800Y290000D03*
G54D55*
X95047Y238996D03*
X97016Y257066D03*
X114733Y238996D03*
X110796D03*
X106859D03*
X102921D03*
X98984D03*
X112764Y257066D03*
X108827D03*
X104890D03*
X100953D03*
G54D73*
X125740Y721650D03*
X123180D03*
X120620D03*
X118060D03*
Y737950D03*
X120620D03*
X123180D03*
X125740D03*
G54D91*
X204910Y586660D03*
Y589220D03*
Y591780D03*
Y594340D03*
X221090D03*
Y591780D03*
Y589220D03*
Y586660D03*
X773638Y98060D03*
Y95500D03*
Y92940D03*
Y90380D03*
Y87820D03*
Y85260D03*
Y82700D03*
Y80140D03*
X795838D03*
Y82700D03*
Y85260D03*
Y87820D03*
Y90380D03*
Y92940D03*
Y95500D03*
Y98060D03*
X776538Y129460D03*
Y126900D03*
Y124340D03*
Y121780D03*
Y119220D03*
Y116660D03*
Y114100D03*
Y111540D03*
X798738D03*
Y114100D03*
Y116660D03*
Y119220D03*
Y121780D03*
Y124340D03*
Y126900D03*
Y129460D03*
G54D37*
X42100Y204900D03*
X57450Y200100D03*
X37700Y414000D03*
X78300Y204800D03*
X92850Y199400D03*
X80000Y736400D03*
X80100Y749300D03*
X80000Y762400D03*
X112932Y268820D03*
X129000Y306400D03*
X122900Y761300D03*
Y756300D03*
X127500Y835000D03*
X139500Y306400D03*
X139701Y411131D03*
X164700Y783000D03*
Y804000D03*
X171900Y748900D03*
Y727900D03*
X210200Y473500D03*
X204200Y704000D03*
Y725000D03*
Y780500D03*
Y759500D03*
X261000Y651900D03*
X343100Y730900D03*
X491688Y7874D03*
Y31496D03*
Y55118D03*
Y78740D03*
X480900Y367800D03*
Y388800D03*
X563731Y384080D03*
X594563Y257608D03*
X652700Y357600D03*
X717963Y-3650D03*
X867552Y741450D03*
X883800Y739800D03*
X885337Y812539D03*
X1042869Y68898D03*
X1062554D03*
X1082239D03*
G54D19*
X28000Y321200D03*
X43300Y394400D03*
X64700Y417000D03*
X87230Y273800D03*
X87685Y489504D03*
Y486004D03*
X75700Y719300D03*
X100800Y306700D03*
X108751Y638436D03*
X124100Y714300D03*
Y710800D03*
X143269Y640420D03*
X143251Y648436D03*
X133751Y643936D03*
X143251D03*
X177821Y598436D03*
X277700Y122000D03*
X274500Y634900D03*
X325292Y295900D03*
X315700Y534500D03*
X619763Y213608D03*
X887600Y51500D03*
X904700Y45000D03*
Y48500D03*
X941981Y25374D03*
X1019063Y17398D03*
X1076700Y57000D03*
Y60500D03*
Y53500D03*
Y50000D03*
X1126100Y129800D03*
Y133300D03*
X1317200Y286500D03*
G54D46*
X48000Y426000D03*
G54D28*
X24050Y691400D03*
X31550Y687525D03*
Y695275D03*
X43950Y690300D03*
X51450Y686425D03*
Y694175D03*
X152435Y331811D03*
X159935Y327936D03*
Y335686D03*
X137167Y333265D03*
X144667Y337140D03*
Y329390D03*
X213607Y130425D03*
X206107Y134300D03*
X213607Y138175D03*
X739750Y44500D03*
X747250Y40625D03*
X762250D03*
X747250Y48375D03*
X754750Y44500D03*
X762250Y48375D03*
X824450Y60025D03*
X816950Y63900D03*
X824450Y67775D03*
X935350Y67400D03*
X942850Y63525D03*
Y71275D03*
G54D82*
X143000Y388000D03*
G54D56*
X71500Y297900D03*
G54D47*
X65700Y430500D03*
Y438500D03*
X47200Y439500D03*
X54800D03*
X60200Y572500D03*
Y564500D03*
X73300Y430500D03*
Y438500D03*
X67800Y572500D03*
Y564500D03*
X120700Y203500D03*
X128300D03*
X120700Y195500D03*
X128300D03*
X120700Y211500D03*
X128300D03*
X127300Y277400D03*
X119700D03*
X150600Y266100D03*
X143000D03*
X229200Y177500D03*
Y169000D03*
Y186000D03*
X231200Y509500D03*
X236800Y177500D03*
X248700Y171922D03*
X256300D03*
X236800Y169000D03*
X248700Y179722D03*
X256300D03*
X248700Y187722D03*
X256300D03*
X236800Y186000D03*
X238800Y509500D03*
X261600Y606400D03*
X254000D03*
X261600Y614400D03*
X254000D03*
X261600Y622400D03*
X254000D03*
X304639Y326201D03*
X312239D03*
X510677Y293740D03*
X518277D03*
X570063Y253608D03*
Y245608D03*
X569200Y375000D03*
X558331Y375080D03*
X550731D03*
X595063Y264108D03*
X602663D03*
X577663Y253608D03*
Y245608D03*
X576800Y375000D03*
X1346300Y240000D03*
X1338700D03*
X1359681Y240509D03*
X1367281D03*
X1359740Y248121D03*
X1367340D03*
G54D65*
X69700Y695200D03*
Y706200D03*
X129189Y324436D03*
Y335436D03*
X216469Y168525D03*
Y179525D03*
G54D74*
X103200Y782300D03*
X108200D03*
X113200D03*
X118200D03*
G54D83*
X150000Y392921D03*
Y390953D03*
Y388984D03*
Y387016D03*
Y385047D03*
Y383079D03*
X136000D03*
Y385047D03*
Y387016D03*
Y388984D03*
Y390953D03*
Y392921D03*
G36*
G01X54403Y250202D02*
G02X54353I-25J-12800D01*
G01Y245802D01*
G03X54403I25J-8400D01*
G01Y250202D01*
G37*
G54D29*
X25100Y746900D03*
Y733400D03*
Y729400D03*
X42300Y276800D03*
Y280900D03*
X35700Y394100D03*
X55800Y483000D03*
Y502000D03*
X55400Y708900D03*
X53200Y770800D03*
X97800Y276300D03*
X67143Y354737D03*
X70800Y506500D03*
Y510500D03*
Y514500D03*
X81000Y529300D03*
X66940Y527270D03*
X80800Y542300D03*
Y546300D03*
X98300Y569500D03*
X80700Y550400D03*
X80800Y554500D03*
Y558500D03*
X98300Y592500D03*
X73800Y586000D03*
X86800Y642000D03*
Y646000D03*
X95000Y681900D03*
X78400Y731300D03*
Y727300D03*
X79600Y740900D03*
Y744900D03*
Y766900D03*
X100800Y298900D03*
Y302900D03*
X112300Y388600D03*
X112234Y441150D03*
X107300Y561500D03*
Y565500D03*
X102500Y681900D03*
X116200Y714300D03*
X99200Y727800D03*
X129000Y745200D03*
X118300Y775000D03*
X149614Y322277D03*
X142113Y322350D03*
X132814Y373985D03*
X157400Y379200D03*
X143298Y420306D03*
X137200Y732300D03*
X164300Y808500D03*
X169084Y186686D03*
Y181686D03*
X194000Y251100D03*
X190615Y289501D03*
X179154Y446672D03*
X171500Y753400D03*
X200560Y289306D03*
X210038Y425645D03*
X209838Y441945D03*
X206000Y446000D03*
X209800Y465000D03*
Y469000D03*
Y482000D03*
Y486000D03*
X209900Y494400D03*
X209800Y490000D03*
Y525500D03*
Y521500D03*
Y554500D03*
X222670Y568020D03*
X230300Y586000D03*
Y590000D03*
X203800Y729500D03*
Y785000D03*
X236300Y139500D03*
X250528Y124804D03*
X253200Y438600D03*
X255900Y422500D03*
X250000Y443300D03*
X252320Y581381D03*
X269800Y126000D03*
X269400Y467300D03*
Y485800D03*
X274600Y638900D03*
X282100Y643900D03*
X311300Y221900D03*
X315700Y542500D03*
X335200Y222000D03*
X334900Y335500D03*
X344600Y318500D03*
X460149Y210989D03*
X496832Y130548D03*
X480809Y339041D03*
Y334041D03*
X480500Y393300D03*
X526600Y165815D03*
Y157715D03*
Y161815D03*
X515709Y202072D03*
X508009Y202172D03*
X522400Y340500D03*
X558270Y136909D03*
X550800Y137597D03*
X558331Y334980D03*
X589763Y215308D03*
X572400Y238400D03*
X619663Y217608D03*
X612163Y213608D03*
X605000Y344200D03*
X663800Y212000D03*
X689200Y212200D03*
X677800Y212000D03*
X722513Y2380D03*
X733063Y31882D03*
X717305Y14964D03*
X720959Y28613D03*
X734930Y63910D03*
X714300Y64000D03*
X713410Y55860D03*
Y51796D03*
X752600Y53800D03*
X757750Y75900D03*
X757900Y86500D03*
Y90600D03*
Y102900D03*
Y82300D03*
X765500Y121200D03*
Y133500D03*
X755800Y118800D03*
X774900Y74000D03*
X794900Y74200D03*
X806800Y86500D03*
Y90600D03*
X835400Y105600D03*
X808713Y118898D03*
X846181Y5499D03*
X861800Y32000D03*
Y40000D03*
X862300Y52800D03*
Y48500D03*
X904800Y37000D03*
X900300Y358500D03*
Y350000D03*
Y345600D03*
X886470Y808230D03*
X928900Y78600D03*
X955381Y64624D03*
X989011Y14160D03*
X989169Y27248D03*
Y23121D03*
X1021360Y2024D03*
X1033416Y33563D03*
X1032192Y11076D03*
X1039967Y11296D03*
X1075859Y5500D03*
Y500D03*
X1051300Y22200D03*
X1075869Y22450D03*
X1076424Y39554D03*
X1075869Y26950D03*
X1076424Y35054D03*
X1075139Y14070D03*
X1054800Y48700D03*
X1049400Y64100D03*
X1120300Y235000D03*
X1134300Y234500D03*
X1148800D03*
X1289300Y300000D03*
X1315300Y274500D03*
X1356800Y278500D03*
G54D92*
X223500Y601500D03*
X906500Y316500D03*
G54D93*
X259500Y152000D03*
X602763Y240858D03*
G54D57*
X83667Y378687D03*
X79792Y371187D03*
X75917Y378687D03*
X112122Y378656D03*
X108247Y371156D03*
X104372Y378656D03*
X469145Y137332D03*
X465270Y129832D03*
X461395Y137332D03*
X464660Y153259D03*
X460785Y145759D03*
X456910Y153259D03*
X499278Y159142D03*
X495403Y151642D03*
X491528Y159142D03*
X513278D03*
X509403Y151642D03*
X505528Y159142D03*
X663756Y204942D03*
X659881Y197442D03*
X656006Y204942D03*
X670006D03*
X691756D03*
X687881Y197442D03*
X684006Y204942D03*
X677756D03*
X673881Y197442D03*
X1121500Y221250D03*
X1125375Y228750D03*
X1117625D03*
X1136000Y221250D03*
X1139875Y228750D03*
X1132125D03*
X1150500Y221250D03*
X1154375Y228750D03*
X1146625D03*
X1301543Y152335D03*
X1305418Y159835D03*
X1297668D03*
X1325530Y140759D03*
X1325220Y121870D03*
X1329095Y129370D03*
X1321345D03*
X1329405Y148259D03*
X1321655D03*
G54D75*
X104750Y813797D03*
Y820203D03*
G54D84*
X145965Y380050D03*
X140047Y395950D03*
Y380050D03*
X145953Y395950D03*
G54D39*
X54083Y308727D03*
Y306758D03*
Y304790D03*
Y302821D03*
Y300853D03*
Y298884D03*
Y296916D03*
Y294947D03*
Y292979D03*
Y291010D03*
Y289042D03*
Y287073D03*
Y285105D03*
Y310695D03*
X88917Y285105D03*
Y287073D03*
Y289042D03*
Y291010D03*
Y292979D03*
Y294947D03*
Y296916D03*
Y298884D03*
Y300853D03*
Y302821D03*
Y304790D03*
Y306758D03*
Y308727D03*
Y310695D03*
G54D48*
X37940Y478700D03*
X40500D03*
X43060D03*
X37940Y471300D03*
X40500D03*
X43060D03*
X58060Y488800D03*
X55500D03*
X52940D03*
X58060Y496200D03*
X55500D03*
X52940D03*
X266540Y472600D03*
Y480000D03*
X271660Y472600D03*
X269100D03*
X271660Y480000D03*
X269100D03*
G54D66*
X86678Y722200D03*
Y720600D03*
G54D76*
X121480Y827000D03*
X135320D03*
G54D49*
X64350Y741790D03*
Y728010D03*
X44250D03*
Y741790D03*
G54D85*
X161050Y734560D03*
Y737120D03*
Y739680D03*
Y742240D03*
X153850Y789660D03*
Y792220D03*
Y794780D03*
Y797340D03*
X193350Y710660D03*
Y713220D03*
Y715780D03*
Y718340D03*
X177350Y742240D03*
Y739680D03*
Y737120D03*
Y734560D03*
X193350Y766160D03*
Y768720D03*
Y771280D03*
Y773840D03*
X170150Y797340D03*
Y794780D03*
Y792220D03*
Y789660D03*
X209650Y713220D03*
Y710660D03*
Y718340D03*
Y715780D03*
Y773840D03*
Y771280D03*
Y768720D03*
Y766160D03*
X470050Y374460D03*
Y377020D03*
Y379580D03*
Y382140D03*
X486350Y377020D03*
Y374460D03*
Y382140D03*
Y379580D03*
G54D67*
X83922Y721400D03*
G54D58*
X90093Y371207D03*
X93968Y378707D03*
X97843Y371207D03*
X85950Y695400D03*
X82075Y687900D03*
X89825D03*
X96075D03*
X99950Y695400D03*
X103825Y687900D03*
X218979Y145011D03*
X222854Y152511D03*
X226729Y145011D03*
X1364343Y173852D03*
X1372093D03*
X1368218Y181352D03*
G54D94*
X259500Y134350D03*
X1337000Y282850D03*
G54D77*
X164400Y204500D03*
X139600D03*
G54D59*
X95148Y399115D03*
X90028D03*
Y405615D03*
X92588D03*
X95148D03*
X76829Y592970D03*
X71709D03*
Y599470D03*
X74269D03*
X76829D03*
X86940Y635250D03*
X92060D03*
Y628750D03*
X89500D03*
X86940D03*
X107368Y399042D03*
X102248D03*
Y405542D03*
X104808D03*
X107368D03*
X296122Y490150D03*
X293562D03*
X291002D03*
Y483650D03*
X296122D03*
G54D86*
X167484Y186086D03*
Y182286D03*
X174084Y186086D03*
Y182286D03*
G54D68*
X97248Y813797D03*
Y820203D03*
G54D95*
X259500Y131650D03*
X1337000Y280150D03*
G54D87*
X196018Y209858D03*
X191018D03*
Y241354D03*
X196018D03*
X206018Y209858D03*
X201018D03*
Y241354D03*
X206018D03*
X534526Y248913D03*
X529526D03*
X524526D03*
X519526D03*
Y280409D03*
X524526D03*
X529526D03*
X534526D03*
G54D96*
X249857Y142157D03*
Y144126D03*
Y146094D03*
Y148063D03*
Y150031D03*
Y152000D03*
Y153969D03*
Y155937D03*
Y157906D03*
Y159874D03*
Y161843D03*
X269143D03*
Y159874D03*
Y157906D03*
Y155937D03*
Y153969D03*
Y152000D03*
Y150031D03*
Y148063D03*
Y146094D03*
Y144126D03*
Y142157D03*
X593120Y231015D03*
Y232984D03*
Y234952D03*
Y236921D03*
Y238889D03*
Y240858D03*
Y242827D03*
Y244795D03*
Y246764D03*
Y248732D03*
Y250701D03*
X612406Y242827D03*
Y240858D03*
Y238889D03*
Y236921D03*
Y234952D03*
Y232984D03*
Y231015D03*
Y250701D03*
Y248732D03*
Y246764D03*
Y244795D03*
X1346643Y273093D03*
Y271124D03*
Y269156D03*
Y267187D03*
Y265219D03*
Y263250D03*
Y261281D03*
Y259313D03*
Y257344D03*
Y255376D03*
Y253407D03*
X1327357D03*
Y255376D03*
Y257344D03*
Y259313D03*
Y261281D03*
Y263250D03*
Y265219D03*
Y267187D03*
Y269156D03*
Y271124D03*
Y273093D03*
G54D78*
X149260Y228500D03*
X156740D03*
Y219500D03*
X153000D03*
X149260D03*
G54D69*
X121504Y248031D03*
G54D79*
X139000Y218419D03*
Y229581D03*
G54D97*
X266231Y245001D03*
X261231D03*
X256231D03*
X251231D03*
X246231D03*
X241231D03*
X236231D03*
Y283559D03*
X241231D03*
X246231D03*
X251231D03*
X256231D03*
X261231D03*
X266231D03*
X271231Y245001D03*
Y283559D03*
X332834Y244932D03*
X327834D03*
X322834D03*
X317834D03*
X312834D03*
X307834D03*
X302834D03*
Y283490D03*
X307834D03*
X312834D03*
X317834D03*
X322834D03*
X327834D03*
X332834D03*
X337834Y244932D03*
Y283490D03*
G54D88*
X235713Y73589D03*
Y68589D03*
Y63589D03*
Y103589D03*
Y98589D03*
Y93589D03*
Y88589D03*
Y83589D03*
Y78589D03*
Y108589D03*
Y118589D03*
Y113589D03*
X250181Y73589D03*
Y68589D03*
Y63589D03*
Y103589D03*
Y98589D03*
Y93589D03*
Y88589D03*
Y83589D03*
Y78589D03*
Y108589D03*
Y118589D03*
Y113589D03*
G54D98*
X263488Y578165D03*
Y583165D03*
Y588165D03*
Y593165D03*
X293229Y343640D03*
Y338640D03*
Y333640D03*
Y328640D03*
X273229D03*
Y333640D03*
Y338640D03*
Y343640D03*
X283488Y578165D03*
Y593165D03*
Y588165D03*
Y583165D03*
X493909Y324041D03*
Y329041D03*
Y334041D03*
Y339041D03*
X513909D03*
Y334041D03*
Y329041D03*
Y324041D03*
X875000Y31000D03*
Y36000D03*
Y41000D03*
Y46000D03*
X895000Y41000D03*
Y36000D03*
Y31000D03*
Y46000D03*
X1001300Y55400D03*
Y60400D03*
Y65400D03*
Y70400D03*
X1021300D03*
Y65400D03*
Y60400D03*
Y55400D03*
G54D89*
X228800Y160600D03*
X217800D03*
X464389Y324210D03*
X475389D03*
G54D99*
X259300Y635900D03*
M02*
